G04*
G04 #@! TF.GenerationSoftware,Altium Limited,Altium Designer,23.7.1 (13)*
G04*
G04 Layer_Color=2752767*
%FSLAX25Y25*%
%MOIN*%
G70*
G04*
G04 #@! TF.SameCoordinates,AF00DCEB-AC48-4C7C-91EA-99F42E284231*
G04*
G04*
G04 #@! TF.FilePolarity,Positive*
G04*
G01*
G75*
%ADD293C,0.00200*%
%ADD294C,0.00267*%
%ADD295C,0.00133*%
D293*
X297232Y-116312D02*
X297632Y-115512D01*
X297232Y-114712D01*
X298031Y-115112D01*
X298832Y-114712D01*
X298431Y-115512D01*
X298832Y-116312D01*
X298031Y-115912D01*
X297232Y-116312D01*
Y-146312D02*
X297632Y-145512D01*
X297232Y-144712D01*
X298031Y-145112D01*
X298832Y-144712D01*
X298431Y-145512D01*
X298832Y-146312D01*
X298031Y-145912D01*
X297232Y-146312D01*
Y-156312D02*
X297632Y-155512D01*
X297232Y-154712D01*
X298031Y-155112D01*
X298832Y-154712D01*
X298431Y-155512D01*
X298832Y-156312D01*
X298031Y-155912D01*
X297232Y-156312D01*
Y-126312D02*
X297632Y-125512D01*
X297232Y-124712D01*
X298031Y-125112D01*
X298832Y-124712D01*
X298431Y-125512D01*
X298832Y-126312D01*
X298031Y-125912D01*
X297232Y-126312D01*
Y-136312D02*
X297632Y-135512D01*
X297232Y-134712D01*
X298031Y-135112D01*
X298832Y-134712D01*
X298431Y-135512D01*
X298832Y-136312D01*
X298031Y-135912D01*
X297232Y-136312D01*
X322593Y-143670D02*
X321260D01*
Y-144670D01*
X321926D01*
X321260D01*
Y-145669D01*
X322593Y-153670D02*
X321260D01*
Y-154670D01*
X321926D01*
X321260D01*
Y-155669D01*
X322593Y-133670D02*
X321260D01*
Y-134670D01*
X321926D01*
X321260D01*
Y-135669D01*
X322593Y-123670D02*
X321260D01*
Y-124670D01*
X321926D01*
X321260D01*
Y-125669D01*
X574010Y7045D02*
Y6645D01*
X574810D01*
Y7045D01*
X575210D01*
Y7845D01*
X574810D01*
Y8245D01*
X574010D01*
Y7845D01*
X573609D01*
Y7045D01*
X574010D01*
Y-9455D02*
Y-9855D01*
X574810D01*
Y-9455D01*
X575210D01*
Y-8655D01*
X574810D01*
Y-8255D01*
X574010D01*
Y-8655D01*
X573609D01*
Y-9455D01*
X574010D01*
X552310Y7045D02*
Y6645D01*
X553110D01*
Y7045D01*
X553510D01*
Y7845D01*
X553110D01*
Y8245D01*
X552310D01*
Y7845D01*
X551909D01*
Y7045D01*
X552310D01*
Y-9455D02*
Y-9855D01*
X553110D01*
Y-9455D01*
X553510D01*
Y-8655D01*
X553110D01*
Y-8255D01*
X552310D01*
Y-8655D01*
X551909D01*
Y-9455D01*
X552310D01*
X1333Y1666D02*
X1000Y1999D01*
X333D01*
X0Y1666D01*
Y333D01*
X333Y0D01*
X1000D01*
X1333Y333D01*
X608268Y-289580D02*
X608668Y-289179D01*
X609068D01*
X608668Y-288779D01*
X609068Y-288380D01*
X608668D01*
X608268Y-287980D01*
X607868Y-288380D01*
X607468D01*
X607868Y-288779D01*
X607468Y-289179D01*
X607868D01*
X608268Y-289580D01*
Y-272060D02*
X608668Y-271660D01*
X609068D01*
X608668Y-271260D01*
X609068Y-270860D01*
X608668D01*
X608268Y-270460D01*
X607868Y-270860D01*
X607468D01*
X607868Y-271260D01*
X607468Y-271660D01*
X607868D01*
X608268Y-272060D01*
X619279Y-264383D02*
X619679D01*
X620079Y-263983D01*
X620479Y-264383D01*
X620879D01*
Y-263983D01*
X620479Y-263583D01*
X620879Y-263183D01*
Y-262783D01*
X620479D01*
X620079Y-263183D01*
X619679Y-262783D01*
X619279D01*
Y-263183D01*
X619679Y-263583D01*
X619279Y-263983D01*
Y-264383D01*
X619679Y-263983D02*
X619879D01*
X620079Y-263783D01*
X620279Y-263983D01*
X620479D01*
Y-263783D01*
X620279Y-263583D01*
X620479Y-263383D01*
Y-263183D01*
X620279D01*
X620079Y-263383D01*
X619879Y-263183D01*
X619679D01*
Y-263383D01*
X619879Y-263583D01*
X619679Y-263783D01*
Y-263983D01*
X619279Y-297257D02*
X619679D01*
X620079Y-296857D01*
X620479Y-297257D01*
X620879D01*
Y-296857D01*
X620479Y-296457D01*
X620879Y-296057D01*
Y-295657D01*
X620479D01*
X620079Y-296057D01*
X619679Y-295657D01*
X619279D01*
Y-296057D01*
X619679Y-296457D01*
X619279Y-296857D01*
Y-297257D01*
X619679Y-296857D02*
X619879D01*
X620079Y-296657D01*
X620279Y-296857D01*
X620479D01*
Y-296657D01*
X620279Y-296457D01*
X620479Y-296257D01*
Y-296057D01*
X620279D01*
X620079Y-296257D01*
X619879Y-296057D01*
X619679D01*
Y-296257D01*
X619879Y-296457D01*
X619679Y-296657D01*
Y-296857D01*
X137497Y-22896D02*
Y-21296D01*
X139097D01*
Y-22896D01*
X137497D01*
Y-70140D02*
Y-68540D01*
X139097D01*
Y-70140D01*
X137497D01*
X196215Y-76347D02*
X194882D01*
Y-78347D01*
X196215D01*
X194882Y-77347D02*
X195548D01*
X576530Y-269359D02*
X575197D01*
Y-271358D01*
X576530D01*
X575197Y-270359D02*
X575863D01*
X353236Y-39776D02*
Y-38176D01*
X354836D01*
Y-39776D01*
X353236D01*
X353636Y-39376D02*
Y-38576D01*
X354435D01*
Y-39376D01*
X353636D01*
X424003Y-39776D02*
Y-38176D01*
X425603D01*
Y-39776D01*
X424003D01*
X424403Y-39376D02*
Y-38576D01*
X425203D01*
Y-39376D01*
X424403D01*
X137497Y-54392D02*
Y-52792D01*
X139097D01*
Y-54392D01*
X137497D01*
X535027Y-113005D02*
Y-111405D01*
X536627D01*
Y-113005D01*
X535027D01*
X535427Y-112605D02*
Y-111805D01*
X536227D01*
Y-112605D01*
X535427D01*
X389662Y-182569D02*
X390062Y-181769D01*
X389662Y-180969D01*
X390462Y-181369D01*
X391262Y-180969D01*
X390862Y-181769D01*
X391262Y-182569D01*
X390462Y-182169D01*
X389662Y-182569D01*
X390062Y-182169D02*
X390262Y-181769D01*
X390062Y-181369D01*
X390462Y-181569D01*
X390862Y-181369D01*
X390662Y-181769D01*
X390862Y-182169D01*
X390462Y-181969D01*
X390062Y-182169D01*
X310922Y-182569D02*
X311322Y-181769D01*
X310922Y-180969D01*
X311722Y-181369D01*
X312522Y-180969D01*
X312122Y-181769D01*
X312522Y-182569D01*
X311722Y-182169D01*
X310922Y-182569D01*
X311322Y-182169D02*
X311522Y-181769D01*
X311322Y-181369D01*
X311722Y-181569D01*
X312122Y-181369D01*
X311922Y-181769D01*
X312122Y-182169D01*
X311722Y-181969D01*
X311322Y-182169D01*
X540293Y-320967D02*
Y-319367D01*
X541893D01*
Y-320967D01*
X540293D01*
X508797D02*
Y-319367D01*
X510397D01*
Y-320967D01*
X508797D01*
X556041D02*
Y-319367D01*
X557641D01*
Y-320967D01*
X556041D01*
X186221Y-332253D02*
Y-334252D01*
X187220D01*
X187553Y-333919D01*
Y-332586D01*
X187220Y-332253D01*
X186221D01*
X198031D02*
Y-334252D01*
X199031D01*
X199364Y-333919D01*
Y-332586D01*
X199031Y-332253D01*
X198031D01*
X58268Y-161780D02*
Y-163779D01*
X59267D01*
X59601Y-163446D01*
Y-162113D01*
X59267Y-161780D01*
X58268D01*
X209842Y-332253D02*
Y-334252D01*
X210842D01*
X211175Y-333919D01*
Y-332586D01*
X210842Y-332253D01*
X209842D01*
X58268Y-321623D02*
Y-323622D01*
X59267D01*
X59601Y-323289D01*
Y-321956D01*
X59267Y-321623D01*
X58268D01*
X218110Y-161780D02*
Y-163779D01*
X219110D01*
X219443Y-163446D01*
Y-162113D01*
X219110Y-161780D01*
X218110D01*
X58268Y-241701D02*
Y-243701D01*
X59267D01*
X59601Y-243368D01*
Y-242035D01*
X59267Y-241701D01*
X58268D01*
X174221Y-332253D02*
Y-334252D01*
X175220D01*
X175553Y-333919D01*
Y-332586D01*
X175220Y-332253D01*
X174221D01*
X218110Y-321623D02*
Y-323622D01*
X219110D01*
X219443Y-323289D01*
Y-321956D01*
X219110Y-321623D01*
X218110D01*
X162221Y-332253D02*
Y-334252D01*
X163220D01*
X163553Y-333919D01*
Y-332586D01*
X163220Y-332253D01*
X162221D01*
X389652Y-330690D02*
X390052Y-329890D01*
X389652Y-329090D01*
X390452Y-329490D01*
X391252Y-329090D01*
X390852Y-329890D01*
X391252Y-330690D01*
X390452Y-330290D01*
X389652Y-330690D01*
X390052Y-330290D02*
X390252Y-329890D01*
X390052Y-329490D01*
X390452Y-329690D01*
X390852Y-329490D01*
X390652Y-329890D01*
X390852Y-330290D01*
X390452Y-330090D01*
X390052Y-330290D01*
X310912Y-330690D02*
X311312Y-329890D01*
X310912Y-329090D01*
X311712Y-329490D01*
X312512Y-329090D01*
X312112Y-329890D01*
X312512Y-330690D01*
X311712Y-330290D01*
X310912Y-330690D01*
X311312Y-330290D02*
X311512Y-329890D01*
X311312Y-329490D01*
X311712Y-329690D01*
X312112Y-329490D01*
X311912Y-329890D01*
X312112Y-330290D01*
X311712Y-330090D01*
X311312Y-330290D01*
X260282Y-295502D02*
X260682Y-294702D01*
X260282Y-293902D01*
X261082Y-294302D01*
X261882Y-293902D01*
X261482Y-294702D01*
X261882Y-295502D01*
X261082Y-295102D01*
X260282Y-295502D01*
X260682Y-295102D02*
X260882Y-294702D01*
X260682Y-294302D01*
X261082Y-294502D01*
X261482Y-294302D01*
X261282Y-294702D01*
X261482Y-295102D01*
X261082Y-294902D01*
X260682Y-295102D01*
X260282Y-216762D02*
X260682Y-215962D01*
X260282Y-215162D01*
X261082Y-215562D01*
X261882Y-215162D01*
X261482Y-215962D01*
X261882Y-216762D01*
X261082Y-216362D01*
X260282Y-216762D01*
X260682Y-216362D02*
X260882Y-215962D01*
X260682Y-215562D01*
X261082Y-215762D01*
X261482Y-215562D01*
X261282Y-215962D01*
X261482Y-216362D01*
X261082Y-216162D01*
X260682Y-216362D01*
X447773Y-216772D02*
X448173Y-215972D01*
X447773Y-215172D01*
X448573Y-215572D01*
X449373Y-215172D01*
X448973Y-215972D01*
X449373Y-216772D01*
X448573Y-216372D01*
X447773Y-216772D01*
X448173Y-216372D02*
X448373Y-215972D01*
X448173Y-215572D01*
X448573Y-215772D01*
X448973Y-215572D01*
X448773Y-215972D01*
X448973Y-216372D01*
X448573Y-216172D01*
X448173Y-216372D01*
X447773Y-295512D02*
X448173Y-294712D01*
X447773Y-293912D01*
X448573Y-294312D01*
X449373Y-293912D01*
X448973Y-294712D01*
X449373Y-295512D01*
X448573Y-295112D01*
X447773Y-295512D01*
X448173Y-295112D02*
X448373Y-294712D01*
X448173Y-294312D01*
X448573Y-294512D01*
X448973Y-294312D01*
X448773Y-294712D01*
X448973Y-295112D01*
X448573Y-294912D01*
X448173Y-295112D01*
X200876Y-313720D02*
Y-315719D01*
X201875D01*
X202209Y-315386D01*
Y-315053D01*
X201875Y-314719D01*
X200876D01*
X201875D01*
X202209Y-314386D01*
Y-314053D01*
X201875Y-313720D01*
X200876D01*
X75768Y-319623D02*
Y-321622D01*
X76767D01*
X77101Y-321289D01*
Y-320956D01*
X76767Y-320622D01*
X75768D01*
X76767D01*
X77101Y-320289D01*
Y-319956D01*
X76767Y-319623D01*
X75768D01*
X78268Y-157780D02*
Y-159780D01*
X79267D01*
X79601Y-159446D01*
Y-159113D01*
X79267Y-158780D01*
X78268D01*
X79267D01*
X79601Y-158447D01*
Y-158113D01*
X79267Y-157780D01*
X78268D01*
X200610Y-169880D02*
Y-171879D01*
X201610D01*
X201943Y-171546D01*
Y-171213D01*
X201610Y-170880D01*
X200610D01*
X201610D01*
X201943Y-170547D01*
Y-170213D01*
X201610Y-169880D01*
X200610D01*
X452793Y-334456D02*
Y-334856D01*
X453593D01*
Y-334456D01*
X453993D01*
Y-333656D01*
X453593D01*
Y-333256D01*
X452793D01*
Y-333656D01*
X452393D01*
Y-334456D01*
X452793D01*
X452993Y-334256D02*
Y-334456D01*
X453393D01*
Y-334256D01*
X453593D01*
Y-333856D01*
X453393D01*
Y-333656D01*
X452993D01*
Y-333856D01*
X452793D01*
Y-334256D01*
X452993D01*
X256193Y-177456D02*
Y-177856D01*
X256993D01*
Y-177456D01*
X257393D01*
Y-176656D01*
X256993D01*
Y-176256D01*
X256193D01*
Y-176656D01*
X255793D01*
Y-177456D01*
X256193D01*
X256393Y-177256D02*
Y-177456D01*
X256793D01*
Y-177256D01*
X256993D01*
Y-176856D01*
X256793D01*
Y-176656D01*
X256393D01*
Y-176856D01*
X256193D01*
Y-177256D01*
X256393D01*
X256293Y-334456D02*
Y-334856D01*
X257093D01*
Y-334456D01*
X257493D01*
Y-333656D01*
X257093D01*
Y-333256D01*
X256293D01*
Y-333656D01*
X255893D01*
Y-334456D01*
X256293D01*
X256493Y-334256D02*
Y-334456D01*
X256893D01*
Y-334256D01*
X257093D01*
Y-333856D01*
X256893D01*
Y-333656D01*
X256493D01*
Y-333856D01*
X256293D01*
Y-334256D01*
X256493D01*
X452793Y-177456D02*
Y-177856D01*
X453593D01*
Y-177456D01*
X453993D01*
Y-176656D01*
X453593D01*
Y-176256D01*
X452793D01*
Y-176656D01*
X452393D01*
Y-177456D01*
X452793D01*
X452993Y-177256D02*
Y-177456D01*
X453393D01*
Y-177256D01*
X453593D01*
Y-176856D01*
X453393D01*
Y-176656D01*
X452993D01*
Y-176856D01*
X452793D01*
Y-177256D01*
X452993D01*
X-18464Y-327581D02*
X-19264Y-325981D01*
X-17664D01*
X-18464Y-327581D01*
Y-327181D02*
X-18865Y-326381D01*
X-18065D01*
X-18464Y-327181D01*
X-8465Y-317581D02*
X-8065Y-317181D01*
X-7665D01*
X-8065Y-316781D01*
X-7665Y-316381D01*
X-8065D01*
X-8465Y-315981D01*
X-8864Y-316381D01*
X-9264D01*
X-8864Y-316781D01*
X-9264Y-317181D01*
X-8864D01*
X-8465Y-317581D01*
Y-317181D02*
X-8264Y-316981D01*
X-8065D01*
X-8264Y-316781D01*
X-8065Y-316581D01*
X-8264D01*
X-8465Y-316381D01*
X-8664Y-316581D01*
X-8864D01*
X-8664Y-316781D01*
X-8864Y-316981D01*
X-8664D01*
X-8465Y-317181D01*
X1535Y-327581D02*
X735Y-325981D01*
X2335D01*
X1535Y-327581D01*
Y-327181D02*
X1135Y-326381D01*
X1936D01*
X1535Y-327181D01*
Y-307581D02*
X735Y-305981D01*
X2335D01*
X1535Y-307581D01*
Y-307181D02*
X1135Y-306381D01*
X1936D01*
X1535Y-307181D01*
X-18464Y-307581D02*
X-19264Y-305981D01*
X-17664D01*
X-18464Y-307581D01*
Y-307181D02*
X-18865Y-306381D01*
X-18065D01*
X-18464Y-307181D01*
X-18465Y-274430D02*
X-19265Y-272830D01*
X-17665D01*
X-18465Y-274430D01*
Y-274030D02*
X-18865Y-273230D01*
X-18065D01*
X-18465Y-274030D01*
X-8465Y-264430D02*
X-8065Y-264030D01*
X-7665D01*
X-8065Y-263630D01*
X-7665Y-263230D01*
X-8065D01*
X-8465Y-262830D01*
X-8865Y-263230D01*
X-9265D01*
X-8865Y-263630D01*
X-9265Y-264030D01*
X-8865D01*
X-8465Y-264430D01*
Y-264030D02*
X-8265Y-263830D01*
X-8065D01*
X-8265Y-263630D01*
X-8065Y-263430D01*
X-8265D01*
X-8465Y-263230D01*
X-8665Y-263430D01*
X-8865D01*
X-8665Y-263630D01*
X-8865Y-263830D01*
X-8665D01*
X-8465Y-264030D01*
X1535Y-274430D02*
X735Y-272830D01*
X2335D01*
X1535Y-274430D01*
Y-274030D02*
X1135Y-273230D01*
X1935D01*
X1535Y-274030D01*
Y-254430D02*
X735Y-252830D01*
X2335D01*
X1535Y-254430D01*
Y-254030D02*
X1135Y-253230D01*
X1935D01*
X1535Y-254030D01*
X-18465Y-254430D02*
X-19265Y-252830D01*
X-17665D01*
X-18465Y-254430D01*
Y-254030D02*
X-18865Y-253230D01*
X-18065D01*
X-18465Y-254030D01*
Y-221280D02*
X-19265Y-219680D01*
X-17665D01*
X-18465Y-221280D01*
Y-220880D02*
X-18865Y-220080D01*
X-18065D01*
X-18465Y-220880D01*
X-8465Y-211280D02*
X-8065Y-210880D01*
X-7665D01*
X-8065Y-210480D01*
X-7665Y-210080D01*
X-8065D01*
X-8465Y-209680D01*
X-8865Y-210080D01*
X-9265D01*
X-8865Y-210480D01*
X-9265Y-210880D01*
X-8865D01*
X-8465Y-211280D01*
Y-210880D02*
X-8265Y-210680D01*
X-8065D01*
X-8265Y-210480D01*
X-8065Y-210280D01*
X-8265D01*
X-8465Y-210080D01*
X-8665Y-210280D01*
X-8865D01*
X-8665Y-210480D01*
X-8865Y-210680D01*
X-8665D01*
X-8465Y-210880D01*
X1535Y-221280D02*
X735Y-219680D01*
X2335D01*
X1535Y-221280D01*
Y-220880D02*
X1135Y-220080D01*
X1935D01*
X1535Y-220880D01*
Y-201280D02*
X735Y-199680D01*
X2335D01*
X1535Y-201280D01*
Y-200880D02*
X1135Y-200080D01*
X1935D01*
X1535Y-200880D01*
X-18465Y-201280D02*
X-19265Y-199680D01*
X-17665D01*
X-18465Y-201280D01*
Y-200880D02*
X-18865Y-200080D01*
X-18065D01*
X-18465Y-200880D01*
X-18464Y-168132D02*
X-19264Y-166532D01*
X-17664D01*
X-18464Y-168132D01*
Y-167732D02*
X-18865Y-166932D01*
X-18065D01*
X-18464Y-167732D01*
X-8465Y-158132D02*
X-8065Y-157732D01*
X-7665D01*
X-8065Y-157332D01*
X-7665Y-156932D01*
X-8065D01*
X-8465Y-156532D01*
X-8864Y-156932D01*
X-9264D01*
X-8864Y-157332D01*
X-9264Y-157732D01*
X-8864D01*
X-8465Y-158132D01*
Y-157732D02*
X-8264Y-157532D01*
X-8065D01*
X-8264Y-157332D01*
X-8065Y-157132D01*
X-8264D01*
X-8465Y-156932D01*
X-8664Y-157132D01*
X-8864D01*
X-8664Y-157332D01*
X-8864Y-157532D01*
X-8664D01*
X-8465Y-157732D01*
X1535Y-168132D02*
X735Y-166532D01*
X2335D01*
X1535Y-168132D01*
Y-167732D02*
X1135Y-166932D01*
X1936D01*
X1535Y-167732D01*
Y-148132D02*
X735Y-146532D01*
X2335D01*
X1535Y-148132D01*
Y-147732D02*
X1135Y-146932D01*
X1936D01*
X1535Y-147732D01*
X-18464Y-148132D02*
X-19264Y-146532D01*
X-17664D01*
X-18464Y-148132D01*
Y-147732D02*
X-18865Y-146932D01*
X-18065D01*
X-18464Y-147732D01*
X608649Y-98989D02*
X609049D01*
X609449Y-98589D01*
X609849Y-98989D01*
X610249D01*
Y-98589D01*
X609849Y-98189D01*
X610249Y-97789D01*
Y-97389D01*
X609849D01*
X609449Y-97789D01*
X609049Y-97389D01*
X608649D01*
Y-97789D01*
X609049Y-98189D01*
X608649Y-98589D01*
Y-98989D01*
Y-108989D02*
X609049D01*
X609449Y-108589D01*
X609849Y-108989D01*
X610249D01*
Y-108589D01*
X609849Y-108189D01*
X610249Y-107789D01*
Y-107389D01*
X609849D01*
X609449Y-107789D01*
X609049Y-107389D01*
X608649D01*
Y-107789D01*
X609049Y-108189D01*
X608649Y-108589D01*
Y-108989D01*
Y-118989D02*
X609049D01*
X609449Y-118589D01*
X609849Y-118989D01*
X610249D01*
Y-118589D01*
X609849Y-118189D01*
X610249Y-117789D01*
Y-117389D01*
X609849D01*
X609449Y-117789D01*
X609049Y-117389D01*
X608649D01*
Y-117789D01*
X609049Y-118189D01*
X608649Y-118589D01*
Y-118989D01*
Y-128989D02*
X609049D01*
X609449Y-128589D01*
X609849Y-128989D01*
X610249D01*
Y-128589D01*
X609849Y-128189D01*
X610249Y-127789D01*
Y-127389D01*
X609849D01*
X609449Y-127789D01*
X609049Y-127389D01*
X608649D01*
Y-127789D01*
X609049Y-128189D01*
X608649Y-128589D01*
Y-128989D01*
Y-138989D02*
X609049D01*
X609449Y-138589D01*
X609849Y-138989D01*
X610249D01*
Y-138589D01*
X609849Y-138189D01*
X610249Y-137789D01*
Y-137389D01*
X609849D01*
X609449Y-137789D01*
X609049Y-137389D01*
X608649D01*
Y-137789D01*
X609049Y-138189D01*
X608649Y-138589D01*
Y-138989D01*
Y-148989D02*
X609049D01*
X609449Y-148589D01*
X609849Y-148989D01*
X610249D01*
Y-148589D01*
X609849Y-148189D01*
X610249Y-147789D01*
Y-147389D01*
X609849D01*
X609449Y-147789D01*
X609049Y-147389D01*
X608649D01*
Y-147789D01*
X609049Y-148189D01*
X608649Y-148589D01*
Y-148989D01*
X618649Y-98989D02*
X619049D01*
X619449Y-98589D01*
X619849Y-98989D01*
X620249D01*
Y-98589D01*
X619849Y-98189D01*
X620249Y-97789D01*
Y-97389D01*
X619849D01*
X619449Y-97789D01*
X619049Y-97389D01*
X618649D01*
Y-97789D01*
X619049Y-98189D01*
X618649Y-98589D01*
Y-98989D01*
Y-108989D02*
X619049D01*
X619449Y-108589D01*
X619849Y-108989D01*
X620249D01*
Y-108589D01*
X619849Y-108189D01*
X620249Y-107789D01*
Y-107389D01*
X619849D01*
X619449Y-107789D01*
X619049Y-107389D01*
X618649D01*
Y-107789D01*
X619049Y-108189D01*
X618649Y-108589D01*
Y-108989D01*
Y-118989D02*
X619049D01*
X619449Y-118589D01*
X619849Y-118989D01*
X620249D01*
Y-118589D01*
X619849Y-118189D01*
X620249Y-117789D01*
Y-117389D01*
X619849D01*
X619449Y-117789D01*
X619049Y-117389D01*
X618649D01*
Y-117789D01*
X619049Y-118189D01*
X618649Y-118589D01*
Y-118989D01*
Y-128989D02*
X619049D01*
X619449Y-128589D01*
X619849Y-128989D01*
X620249D01*
Y-128589D01*
X619849Y-128189D01*
X620249Y-127789D01*
Y-127389D01*
X619849D01*
X619449Y-127789D01*
X619049Y-127389D01*
X618649D01*
Y-127789D01*
X619049Y-128189D01*
X618649Y-128589D01*
Y-128989D01*
Y-138989D02*
X619049D01*
X619449Y-138589D01*
X619849Y-138989D01*
X620249D01*
Y-138589D01*
X619849Y-138189D01*
X620249Y-137789D01*
Y-137389D01*
X619849D01*
X619449Y-137789D01*
X619049Y-137389D01*
X618649D01*
Y-137789D01*
X619049Y-138189D01*
X618649Y-138589D01*
Y-138989D01*
Y-148989D02*
X619049D01*
X619449Y-148589D01*
X619849Y-148989D01*
X620249D01*
Y-148589D01*
X619849Y-148189D01*
X620249Y-147789D01*
Y-147389D01*
X619849D01*
X619449Y-147789D01*
X619049Y-147389D01*
X618649D01*
Y-147789D01*
X619049Y-148189D01*
X618649Y-148589D01*
Y-148989D01*
X1333Y-376729D02*
X1000Y-376396D01*
X333D01*
X0Y-376729D01*
Y-378062D01*
X333Y-378395D01*
X1000D01*
X1333Y-378062D01*
X181534Y-387757D02*
Y-386424D01*
X182200Y-385758D01*
X182867Y-386424D01*
Y-387757D01*
Y-386757D01*
X181534D01*
X522047Y-270866D02*
Y-269533D01*
X522714Y-268867D01*
X523380Y-269533D01*
Y-270866D01*
Y-269866D01*
X522047D01*
X496620Y-310492D02*
Y-309159D01*
X497286Y-308493D01*
X497953Y-309159D01*
Y-310492D01*
Y-309492D01*
X496620D01*
X61811Y787D02*
Y2120D01*
X62477Y2787D01*
X63144Y2120D01*
Y787D01*
Y1787D01*
X61811D01*
X593307Y-292126D02*
Y-290793D01*
X593973Y-290127D01*
X594640Y-290793D01*
Y-292126D01*
Y-291126D01*
X593307D01*
X245325Y-120837D02*
Y-119504D01*
X245991Y-118838D01*
X246658Y-119504D01*
Y-120837D01*
Y-119837D01*
X245325D01*
X500049Y-256633D02*
Y-255301D01*
X500716Y-254634D01*
X501382Y-255301D01*
Y-256633D01*
Y-255634D01*
X500049D01*
X585039Y-266142D02*
Y-264809D01*
X585706Y-264142D01*
X586372Y-264809D01*
Y-266142D01*
Y-265142D01*
X585039D01*
X560630Y-269291D02*
Y-267958D01*
X561296Y-267292D01*
X561963Y-267958D01*
Y-269291D01*
Y-268292D01*
X560630D01*
X599044Y-275032D02*
Y-273699D01*
X599711Y-273032D01*
X600377Y-273699D01*
Y-275032D01*
Y-274032D01*
X599044D01*
X585039Y-272835D02*
Y-271502D01*
X585706Y-270835D01*
X586372Y-271502D01*
Y-272835D01*
Y-271835D01*
X585039D01*
X581496Y-272835D02*
Y-271502D01*
X582163Y-270835D01*
X582829Y-271502D01*
Y-272835D01*
Y-271835D01*
X581496D01*
X548425Y-269632D02*
Y-268299D01*
X549092Y-267632D01*
X549758Y-268299D01*
Y-269632D01*
Y-268632D01*
X548425D01*
X541093Y-284626D02*
Y-283294D01*
X541760Y-282627D01*
X542426Y-283294D01*
Y-284626D01*
Y-283627D01*
X541093D01*
X541411Y-269932D02*
Y-268599D01*
X542078Y-267933D01*
X542744Y-268599D01*
Y-269932D01*
Y-268932D01*
X541411D01*
X536489Y-269182D02*
Y-267849D01*
X537155Y-267182D01*
X537822Y-267849D01*
Y-269182D01*
Y-268182D01*
X536489D01*
X554724Y-272441D02*
Y-271108D01*
X555391Y-270442D01*
X556057Y-271108D01*
Y-272441D01*
Y-271441D01*
X554724D01*
X555460Y-284401D02*
Y-283068D01*
X556126Y-282401D01*
X556793Y-283068D01*
Y-284401D01*
Y-283401D01*
X555460D01*
X574406Y-280807D02*
Y-279474D01*
X575072Y-278807D01*
X575739Y-279474D01*
Y-280807D01*
Y-279807D01*
X574406D01*
X567525Y-286203D02*
Y-284870D01*
X568192Y-284204D01*
X568858Y-284870D01*
Y-286203D01*
Y-285203D01*
X567525D01*
X581890Y-290158D02*
Y-288825D01*
X582556Y-288158D01*
X583223Y-288825D01*
Y-290158D01*
Y-289158D01*
X581890D01*
X583815Y-275386D02*
Y-274053D01*
X584481Y-273387D01*
X585148Y-274053D01*
Y-275386D01*
Y-274386D01*
X583815D01*
X614822Y-250158D02*
Y-248825D01*
X615489Y-248159D01*
X616155Y-248825D01*
Y-250158D01*
Y-249158D01*
X614822D01*
X604724Y-274803D02*
Y-273470D01*
X605391Y-272804D01*
X606057Y-273470D01*
Y-274803D01*
Y-273803D01*
X604724D01*
X321260Y-166142D02*
Y-164809D01*
X321926Y-164142D01*
X322593Y-164809D01*
Y-166142D01*
Y-165142D01*
X321260D01*
X323622Y-166535D02*
Y-165202D01*
X324289Y-164536D01*
X324955Y-165202D01*
Y-166535D01*
Y-165536D01*
X323622D01*
X150394Y-140157D02*
Y-138825D01*
X151060Y-138158D01*
X151727Y-138825D01*
Y-140157D01*
Y-139158D01*
X150394D01*
X317323Y-114961D02*
Y-113628D01*
X317989Y-112961D01*
X318656Y-113628D01*
Y-114961D01*
Y-113961D01*
X317323D01*
X321260Y-114961D02*
Y-113628D01*
X321926Y-112961D01*
X322593Y-113628D01*
Y-114961D01*
Y-113961D01*
X321260D01*
X320761Y-183851D02*
Y-182518D01*
X321428Y-181852D01*
X322094Y-182518D01*
Y-183851D01*
Y-182852D01*
X320761D01*
X309449Y-211811D02*
Y-210478D01*
X310115Y-209812D01*
X310782Y-210478D01*
Y-211811D01*
Y-210811D01*
X309449D01*
X313386Y-212598D02*
Y-211265D01*
X314052Y-210599D01*
X314719Y-211265D01*
Y-212598D01*
Y-211599D01*
X313386D01*
X124016Y-110236D02*
Y-108903D01*
X124682Y-108237D01*
X125349Y-108903D01*
Y-110236D01*
Y-109237D01*
X124016D01*
X222351Y-98694D02*
Y-97361D01*
X223017Y-96694D01*
X223684Y-97361D01*
Y-98694D01*
Y-97694D01*
X222351D01*
X245276Y-115748D02*
Y-114415D01*
X245942Y-113749D01*
X246608Y-114415D01*
Y-115748D01*
Y-114748D01*
X245276D01*
X211648Y-103695D02*
Y-102362D01*
X212315Y-101695D01*
X212981Y-102362D01*
Y-103695D01*
Y-102695D01*
X211648D01*
X44001Y-137747D02*
Y-136414D01*
X44667Y-135747D01*
X45333Y-136414D01*
Y-137747D01*
Y-136747D01*
X44001D01*
X100729Y-127872D02*
Y-126539D01*
X101396Y-125872D01*
X102062Y-126539D01*
Y-127872D01*
Y-126872D01*
X100729D01*
X-23622Y-181102D02*
Y-179770D01*
X-22956Y-179103D01*
X-22289Y-179770D01*
Y-181102D01*
Y-180103D01*
X-23622D01*
X98761Y-129872D02*
Y-128539D01*
X99427Y-127873D01*
X100094Y-128539D01*
Y-129872D01*
Y-128872D01*
X98761D01*
X57422Y-128927D02*
Y-127594D01*
X58089Y-126928D01*
X58755Y-127594D01*
Y-128927D01*
Y-127927D01*
X57422D01*
X89312Y-128140D02*
Y-126807D01*
X89978Y-126140D01*
X90645Y-126807D01*
Y-128140D01*
Y-127140D01*
X89312D01*
X84981Y-128140D02*
Y-126807D01*
X85648Y-126140D01*
X86314Y-126807D01*
Y-128140D01*
Y-127140D01*
X84981D01*
X80651Y-128140D02*
Y-126807D01*
X81317Y-126140D01*
X81984Y-126807D01*
Y-128140D01*
Y-127140D01*
X80651D01*
X89312Y-123809D02*
Y-122476D01*
X89978Y-121810D01*
X90645Y-122476D01*
Y-123809D01*
Y-122809D01*
X89312D01*
X84981Y-123809D02*
Y-122476D01*
X85648Y-121810D01*
X86314Y-122476D01*
Y-123809D01*
Y-122809D01*
X84981D01*
X80651Y-123809D02*
Y-122476D01*
X81317Y-121810D01*
X81984Y-122476D01*
Y-123809D01*
Y-122809D01*
X80651D01*
X89312Y-119478D02*
Y-118146D01*
X89978Y-117479D01*
X90645Y-118146D01*
Y-119478D01*
Y-118479D01*
X89312D01*
X84981Y-119478D02*
Y-118146D01*
X85648Y-117479D01*
X86314Y-118146D01*
Y-119478D01*
Y-118479D01*
X84981D01*
X80651Y-119478D02*
Y-118146D01*
X81317Y-117479D01*
X81984Y-118146D01*
Y-119478D01*
Y-118479D01*
X80651D01*
X98761Y-125872D02*
Y-124539D01*
X99427Y-123872D01*
X100094Y-124539D01*
Y-125872D01*
Y-124872D01*
X98761D01*
X58407Y-137589D02*
Y-136256D01*
X59073Y-135589D01*
X59739Y-136256D01*
Y-137589D01*
Y-136589D01*
X58407D01*
X85044Y-139557D02*
Y-138224D01*
X85711Y-137558D01*
X86377Y-138224D01*
Y-139557D01*
Y-138557D01*
X85044D01*
X81044Y-139557D02*
Y-138224D01*
X81711Y-137558D01*
X82377Y-138224D01*
Y-139557D01*
Y-138557D01*
X81044D01*
X89044Y-139557D02*
Y-138224D01*
X89711Y-137558D01*
X90377Y-138224D01*
Y-139557D01*
Y-138557D01*
X89044D01*
X71202Y-138095D02*
Y-136762D01*
X71868Y-136096D01*
X72535Y-136762D01*
Y-138095D01*
Y-137095D01*
X71202D01*
X79044Y-137936D02*
Y-136603D01*
X79711Y-135936D01*
X80377Y-136603D01*
Y-137936D01*
Y-136936D01*
X79044D01*
X83044Y-137936D02*
Y-136603D01*
X83711Y-135936D01*
X84377Y-136603D01*
Y-137936D01*
Y-136936D01*
X83044D01*
X91044Y-137936D02*
Y-136603D01*
X91711Y-135936D01*
X92377Y-136603D01*
Y-137936D01*
Y-136936D01*
X91044D01*
X87044Y-137936D02*
Y-136603D01*
X87711Y-135936D01*
X88377Y-136603D01*
Y-137936D01*
Y-136936D01*
X87044D01*
X68889Y-137453D02*
Y-136121D01*
X69556Y-135454D01*
X70222Y-136121D01*
Y-137453D01*
Y-136454D01*
X68889D01*
X98761Y-117746D02*
Y-116413D01*
X99427Y-115747D01*
X100094Y-116413D01*
Y-117746D01*
Y-116746D01*
X98761D01*
Y-121871D02*
Y-120539D01*
X99427Y-119872D01*
X100094Y-120539D01*
Y-121871D01*
Y-120872D01*
X98761D01*
X52501Y-119872D02*
Y-118539D01*
X53167Y-117873D01*
X53834Y-118539D01*
Y-119872D01*
Y-118872D01*
X52501D01*
X44134Y-115080D02*
Y-113747D01*
X44800Y-113081D01*
X45467Y-113747D01*
Y-115080D01*
Y-114080D01*
X44134D01*
X44621Y-110628D02*
Y-109295D01*
X45288Y-108628D01*
X45954Y-109295D01*
Y-110628D01*
Y-109628D01*
X44621D01*
X58210Y-108061D02*
Y-106728D01*
X58876Y-106062D01*
X59543Y-106728D01*
Y-108061D01*
Y-107061D01*
X58210D01*
X91044Y-110061D02*
Y-108728D01*
X91711Y-108062D01*
X92377Y-108728D01*
Y-110061D01*
Y-109061D01*
X91044D01*
X78918Y-110029D02*
Y-108697D01*
X79585Y-108030D01*
X80251Y-108697D01*
Y-110029D01*
Y-109030D01*
X78918D01*
X82918Y-110029D02*
Y-108697D01*
X83585Y-108030D01*
X84251Y-108697D01*
Y-110029D01*
Y-109030D01*
X82918D01*
X86981Y-110029D02*
Y-108697D01*
X87648Y-108030D01*
X88314Y-108697D01*
Y-110029D01*
Y-109030D01*
X86981D01*
X80981Y-108061D02*
Y-106728D01*
X81648Y-106062D01*
X82314Y-106728D01*
Y-108061D01*
Y-107061D01*
X80981D01*
X88981Y-108061D02*
Y-106728D01*
X89648Y-106062D01*
X90314Y-106728D01*
Y-108061D01*
Y-107061D01*
X88981D01*
X84981Y-108061D02*
Y-106728D01*
X85648Y-106062D01*
X86314Y-106728D01*
Y-108061D01*
Y-107061D01*
X84981D01*
X139370Y-119698D02*
X138570Y-118098D01*
X140170D01*
X139370Y-119698D01*
X262724Y-107813D02*
Y-106480D01*
X263390Y-105813D01*
X264056Y-106480D01*
Y-107813D01*
Y-106813D01*
X262724D01*
X253082Y-110236D02*
Y-108903D01*
X253748Y-108237D01*
X254415Y-108903D01*
Y-110236D01*
Y-109237D01*
X253082D01*
X317828Y-161260D02*
Y-159927D01*
X318495Y-159260D01*
X319161Y-159927D01*
Y-161260D01*
Y-160260D01*
X317828D01*
X313878Y-161597D02*
Y-160264D01*
X314545Y-159597D01*
X315211Y-160264D01*
Y-161597D01*
Y-160597D01*
X313878D01*
X286221Y-125603D02*
X285420Y-124003D01*
X287020D01*
X286221Y-125603D01*
X285827Y-138595D02*
X285027Y-136995D01*
X286627D01*
X285827Y-138595D01*
X285384Y-155292D02*
X284584Y-153692D01*
X286184D01*
X285384Y-155292D01*
X284646Y-129147D02*
X283846Y-127547D01*
X285446D01*
X284646Y-129147D01*
X284252Y-144895D02*
X283452Y-143295D01*
X285052D01*
X284252Y-144895D01*
X282058Y-152017D02*
X281258Y-150417D01*
X282858D01*
X282058Y-152017D01*
X281890Y-156705D02*
X281090Y-155105D01*
X282690D01*
X281890Y-156705D01*
X281496Y-125209D02*
X280696Y-123609D01*
X282296D01*
X281496Y-125209D01*
X280709Y-138595D02*
X279909Y-136995D01*
X281509D01*
X280709Y-138595D01*
X276650Y-129610D02*
X275850Y-128010D01*
X277450D01*
X276650Y-129610D01*
X276083Y-153359D02*
X275283Y-151759D01*
X276883D01*
X276083Y-153359D01*
Y-141942D02*
X275283Y-140342D01*
X276883D01*
X276083Y-141942D01*
X255906Y-127178D02*
X255105Y-125578D01*
X256705D01*
X255906Y-127178D01*
Y-132296D02*
X255105Y-130696D01*
X256705D01*
X255906Y-132296D01*
Y-137808D02*
X255105Y-136208D01*
X256705D01*
X255906Y-137808D01*
Y-142926D02*
X255105Y-141326D01*
X256705D01*
X255906Y-142926D01*
X257480Y-151194D02*
X256680Y-149594D01*
X258280D01*
X257480Y-151194D01*
X255512Y-147650D02*
X254712Y-146050D01*
X256312D01*
X255512Y-147650D01*
X140551Y-117335D02*
X139751Y-115735D01*
X141351D01*
X140551Y-117335D01*
X368110Y-330315D02*
Y-328982D01*
X368777Y-328316D01*
X369443Y-328982D01*
Y-330315D01*
Y-329315D01*
X368110D01*
X262006Y-387255D02*
Y-385922D01*
X262673Y-385256D01*
X263339Y-385922D01*
Y-387255D01*
Y-386256D01*
X262006D01*
X365354Y-330315D02*
Y-328982D01*
X366021Y-328316D01*
X366687Y-328982D01*
Y-330315D01*
Y-329315D01*
X365354D01*
X265158Y-387253D02*
Y-385921D01*
X265824Y-385254D01*
X266490Y-385921D01*
Y-387253D01*
Y-386254D01*
X265158D01*
X374114Y-346144D02*
Y-344812D01*
X374781Y-344145D01*
X375447Y-344812D01*
Y-346144D01*
Y-345145D01*
X374114D01*
X246339Y-386975D02*
Y-385642D01*
X247005Y-384976D01*
X247672Y-385642D01*
Y-386975D01*
Y-385975D01*
X246339D01*
X249410Y-387253D02*
Y-385921D01*
X250076Y-385254D01*
X250742Y-385921D01*
Y-387253D01*
Y-386254D01*
X249410D01*
X371359Y-346144D02*
Y-344812D01*
X372025Y-344145D01*
X372691Y-344812D01*
Y-346144D01*
Y-345145D01*
X371359D01*
X237992Y-374655D02*
Y-373322D01*
X238659Y-372656D01*
X239325Y-373322D01*
Y-374655D01*
Y-373655D01*
X237992D01*
X367422Y-346144D02*
Y-344812D01*
X368088Y-344145D01*
X368755Y-344812D01*
Y-346144D01*
Y-345145D01*
X367422D01*
X241929Y-374655D02*
Y-373322D01*
X242596Y-372656D01*
X243262Y-373322D01*
Y-374655D01*
Y-373655D01*
X241929D01*
X364666Y-346144D02*
Y-344812D01*
X365332Y-344145D01*
X365999Y-344812D01*
Y-346144D01*
Y-345145D01*
X364666D01*
X354036Y-346144D02*
Y-344812D01*
X354702Y-344145D01*
X355369Y-344812D01*
Y-346144D01*
Y-345145D01*
X354036D01*
X206496Y-374655D02*
Y-373322D01*
X207162Y-372656D01*
X207829Y-373322D01*
Y-374655D01*
Y-373655D01*
X206496D01*
X351280Y-346144D02*
Y-344812D01*
X351946Y-344145D01*
X352613Y-344812D01*
Y-346144D01*
Y-345145D01*
X351280D01*
X210433Y-374655D02*
Y-373322D01*
X211100Y-372656D01*
X211766Y-373322D01*
Y-374655D01*
Y-373655D01*
X210433D01*
X360729Y-346144D02*
Y-344812D01*
X361395Y-344145D01*
X362062Y-344812D01*
Y-346144D01*
Y-345145D01*
X360729D01*
X229331Y-387253D02*
Y-385921D01*
X229997Y-385254D01*
X230664Y-385921D01*
Y-387253D01*
Y-386254D01*
X229331D01*
X357973Y-346144D02*
Y-344812D01*
X358639Y-344145D01*
X359306Y-344812D01*
Y-346144D01*
Y-345145D01*
X357973D01*
X232480Y-387253D02*
Y-385921D01*
X233147Y-385254D01*
X233813Y-385921D01*
Y-387253D01*
Y-386254D01*
X232480D01*
X212795Y-387253D02*
Y-385921D01*
X213462Y-385254D01*
X214128Y-385921D01*
Y-387253D01*
Y-386254D01*
X212795D01*
X215945Y-387253D02*
Y-385921D01*
X216611Y-385254D01*
X217278Y-385921D01*
Y-387253D01*
Y-386254D01*
X215945D01*
X356299Y-330315D02*
Y-328982D01*
X356966Y-328316D01*
X357632Y-328982D01*
Y-330315D01*
Y-329315D01*
X356299D01*
X353543Y-330315D02*
Y-328982D01*
X354210Y-328316D01*
X354876Y-328982D01*
Y-330315D01*
Y-329315D01*
X353543D01*
X218445Y-374108D02*
Y-372775D01*
X219111Y-372108D01*
X219778Y-372775D01*
Y-374108D01*
Y-373108D01*
X218445D01*
X222638Y-374655D02*
Y-373322D01*
X223304Y-372656D01*
X223971Y-373322D01*
Y-374655D01*
Y-373655D01*
X222638D01*
X364567Y-327178D02*
X363767Y-325578D01*
X365367D01*
X364567Y-327178D01*
X357575Y-328576D02*
X356775Y-326976D01*
X358375D01*
X357575Y-328576D01*
X357480Y-333477D02*
X356680Y-331877D01*
X358280D01*
X357480Y-333477D01*
X350787Y-330721D02*
X349987Y-329121D01*
X351587D01*
X350787Y-330721D01*
X359652Y-326841D02*
Y-325508D01*
X360318Y-324842D01*
X360985Y-325508D01*
Y-326841D01*
Y-325842D01*
X359652D01*
X362408Y-326841D02*
Y-325508D01*
X363074Y-324842D01*
X363741Y-325508D01*
Y-326841D01*
Y-325842D01*
X362408D01*
X205906Y-373241D02*
X205105Y-371641D01*
X206705D01*
X205906Y-373241D01*
X211024D02*
X210224Y-371641D01*
X211824D01*
X211024Y-373241D01*
X222835Y-372847D02*
X222035Y-371247D01*
X223635D01*
X222835Y-372847D01*
X217323Y-372453D02*
X216523Y-370853D01*
X218123D01*
X217323Y-372453D01*
X237795D02*
X236995Y-370853D01*
X238595D01*
X237795Y-372453D01*
X242897Y-372664D02*
X242097Y-371064D01*
X243697D01*
X242897Y-372664D01*
X250394Y-376784D02*
X249594Y-375184D01*
X251194D01*
X250394Y-376784D01*
X259449Y-374028D02*
X258649Y-372428D01*
X260249D01*
X259449Y-374028D01*
X268504Y-372847D02*
X267704Y-371247D01*
X269304D01*
X268504Y-372847D01*
X274803Y-373241D02*
X274003Y-371641D01*
X275603D01*
X274803Y-373241D01*
X266929Y-385839D02*
X266129Y-384239D01*
X267729D01*
X266929Y-385839D01*
X243701Y-390170D02*
X242901Y-388570D01*
X244501D01*
X243701Y-390170D01*
X250394Y-385446D02*
X249594Y-383846D01*
X251194D01*
X250394Y-385446D01*
X227953Y-384658D02*
X227153Y-383058D01*
X228753D01*
X227953Y-384658D01*
X233858Y-385446D02*
X233058Y-383846D01*
X234658D01*
X233858Y-385446D01*
X213386D02*
X212586Y-383846D01*
X214186D01*
X213386Y-385446D01*
X513386Y-199213D02*
Y-197880D01*
X514052Y-197213D01*
X514719Y-197880D01*
Y-199213D01*
Y-198213D01*
X513386D01*
X521654Y-198819D02*
Y-197486D01*
X522320Y-196820D01*
X522986Y-197486D01*
Y-198819D01*
Y-197819D01*
X521654D01*
X591339Y-189764D02*
Y-188431D01*
X592005Y-187764D01*
X592671Y-188431D01*
Y-189764D01*
Y-188764D01*
X591339D01*
X153225Y-121747D02*
Y-120414D01*
X153892Y-119747D01*
X154558Y-120414D01*
Y-121747D01*
Y-120747D01*
X153225D01*
X133099Y-136519D02*
Y-135186D01*
X133765Y-134520D01*
X134432Y-135186D01*
Y-136519D01*
Y-135520D01*
X133099D01*
X24500Y-9229D02*
X23700Y-7629D01*
X25300D01*
X24500Y-9229D01*
X603150Y-235946D02*
Y-234613D01*
X603816Y-233946D01*
X604483Y-234613D01*
Y-235946D01*
Y-234946D01*
X603150D01*
X604316Y-246600D02*
Y-245267D01*
X604983Y-244600D01*
X605649Y-245267D01*
Y-246600D01*
Y-245600D01*
X604316D01*
X152756Y-65354D02*
Y-64021D01*
X153422Y-63355D01*
X154089Y-64021D01*
Y-65354D01*
Y-64355D01*
X152756D01*
Y-57480D02*
Y-56147D01*
X153422Y-55481D01*
X154089Y-56147D01*
Y-57480D01*
Y-56481D01*
X152756D01*
Y-49606D02*
Y-48273D01*
X153422Y-47607D01*
X154089Y-48273D01*
Y-49606D01*
Y-48607D01*
X152756D01*
X157480Y-73228D02*
Y-71895D01*
X158147Y-71229D01*
X158813Y-71895D01*
Y-73228D01*
Y-72229D01*
X157480D01*
X284646Y-291732D02*
Y-290399D01*
X285312Y-289733D01*
X285979Y-290399D01*
Y-291732D01*
Y-290733D01*
X284646D01*
X381890Y-183858D02*
Y-182525D01*
X382556Y-181859D01*
X383223Y-182525D01*
Y-183858D01*
Y-182859D01*
X381890D01*
X384646Y-184252D02*
Y-182919D01*
X385312Y-182253D01*
X385979Y-182919D01*
Y-184252D01*
Y-183252D01*
X384646D01*
X359842Y-161824D02*
X359043Y-160224D01*
X360643D01*
X359842Y-161824D01*
X363386Y-161430D02*
X362586Y-159830D01*
X364186D01*
X363386Y-161430D01*
X367717D02*
X366916Y-159830D01*
X368516D01*
X367717Y-161430D01*
X454775Y-308565D02*
Y-307233D01*
X455442Y-306566D01*
X456108Y-307233D01*
Y-308565D01*
Y-307566D01*
X454775D01*
X569685Y-303150D02*
Y-301817D01*
X570352Y-301150D01*
X571018Y-301817D01*
Y-303150D01*
Y-302150D01*
X569685D01*
X608268Y-84252D02*
Y-82919D01*
X608934Y-82253D01*
X609601Y-82919D01*
Y-84252D01*
Y-83252D01*
X608268D01*
X383083Y-161839D02*
Y-160506D01*
X383749Y-159840D01*
X384416Y-160506D01*
Y-161839D01*
Y-160839D01*
X383083D01*
X421313Y-174784D02*
Y-173451D01*
X421979Y-172785D01*
X422646Y-173451D01*
Y-174784D01*
Y-173785D01*
X421313D01*
X396850Y-249016D02*
Y-247683D01*
X397517Y-247016D01*
X398183Y-247683D01*
Y-249016D01*
Y-248016D01*
X396850D01*
X129063Y-136618D02*
Y-135285D01*
X129730Y-134618D01*
X130396Y-135285D01*
Y-136618D01*
Y-135618D01*
X129063D01*
X38613Y-53355D02*
Y-52022D01*
X39279Y-51356D01*
X39946Y-52022D01*
Y-53355D01*
Y-52356D01*
X38613D01*
X172674Y-138386D02*
Y-137053D01*
X173340Y-136387D01*
X174007Y-137053D01*
Y-138386D01*
Y-137386D01*
X172674D01*
X613406Y-89494D02*
Y-88161D01*
X614072Y-87495D01*
X614738Y-88161D01*
Y-89494D01*
Y-88495D01*
X613406D01*
X388189Y-162205D02*
Y-160872D01*
X388855Y-160205D01*
X389522Y-160872D01*
Y-162205D01*
Y-161205D01*
X388189D01*
X419798Y-176745D02*
Y-175412D01*
X420464Y-174745D01*
X421131Y-175412D01*
Y-176745D01*
Y-175745D01*
X419798D01*
X401575Y-249213D02*
Y-247880D01*
X402241Y-247213D01*
X402908Y-247880D01*
Y-249213D01*
Y-248213D01*
X401575D01*
X126307Y-136224D02*
Y-134891D01*
X126974Y-134225D01*
X127640Y-134891D01*
Y-136224D01*
Y-135224D01*
X126307D01*
X38583Y-58355D02*
Y-57023D01*
X39249Y-56356D01*
X39916Y-57023D01*
Y-58355D01*
Y-57356D01*
X38583D01*
X170311Y-139961D02*
Y-138628D01*
X170978Y-137961D01*
X171644Y-138628D01*
Y-139961D01*
Y-138961D01*
X170311D01*
X491732Y-150013D02*
X490932Y-148413D01*
X492532D01*
X491732Y-150013D01*
X500394Y-146469D02*
X499594Y-144869D01*
X501194D01*
X500394Y-146469D01*
X496063Y-146076D02*
X495263Y-144476D01*
X496863D01*
X496063Y-146076D01*
X491732D02*
X490932Y-144476D01*
X492532D01*
X491732Y-146076D01*
X550391Y-243310D02*
Y-241977D01*
X551057Y-241311D01*
X551724Y-241977D01*
Y-243310D01*
Y-242310D01*
X550391D01*
X477165Y-247244D02*
Y-245911D01*
X477832Y-245245D01*
X478498Y-245911D01*
Y-247244D01*
Y-246244D01*
X477165D01*
X539370Y-229540D02*
X538570Y-227940D01*
X540170D01*
X539370Y-229540D01*
X542913D02*
X542113Y-227940D01*
X543713D01*
X542913Y-229540D01*
X561024Y-184265D02*
X560224Y-182665D01*
X561824D01*
X561024Y-184265D01*
Y-187414D02*
X560224Y-185814D01*
X561824D01*
X561024Y-187414D01*
X-4724Y-283071D02*
Y-281738D01*
X-4058Y-281071D01*
X-3391Y-281738D01*
Y-283071D01*
Y-282071D01*
X-4724D01*
X35433Y-130328D02*
X34633Y-128728D01*
X36233D01*
X35433Y-130328D01*
X32283D02*
X31484Y-128728D01*
X33084D01*
X32283Y-130328D01*
X28740D02*
X27940Y-128728D01*
X29540D01*
X28740Y-130328D01*
X35433Y-50787D02*
Y-49455D01*
X36099Y-48788D01*
X36766Y-49455D01*
Y-50787D01*
Y-49788D01*
X35433D01*
X149935Y-124206D02*
Y-122873D01*
X150601Y-122206D01*
X151268Y-122873D01*
Y-124206D01*
Y-123206D01*
X149935D01*
X150233Y-119882D02*
Y-118549D01*
X150899Y-117883D01*
X151566Y-118549D01*
Y-119882D01*
Y-118882D01*
X150233D01*
X429528Y-231496D02*
Y-230163D01*
X430194Y-229497D01*
X430861Y-230163D01*
Y-231496D01*
Y-230496D01*
X429528D01*
X364173Y-280315D02*
Y-278982D01*
X364840Y-278316D01*
X365506Y-278982D01*
Y-280315D01*
Y-279315D01*
X364173D01*
X462205Y-255118D02*
Y-253785D01*
X462871Y-253119D01*
X463538Y-253785D01*
Y-255118D01*
Y-254118D01*
X462205D01*
X464961Y-125197D02*
Y-123864D01*
X465627Y-123197D01*
X466293Y-123864D01*
Y-125197D01*
Y-124197D01*
X464961D01*
X50000Y-44094D02*
Y-42762D01*
X50666Y-42095D01*
X51333Y-42762D01*
Y-44094D01*
Y-43095D01*
X50000D01*
X324016Y-43713D02*
X323216Y-42113D01*
X324816D01*
X324016Y-43713D01*
X318898Y-44107D02*
X318098Y-42507D01*
X319698D01*
X318898Y-44107D01*
X324016Y-40564D02*
X323216Y-38964D01*
X324816D01*
X324016Y-40564D01*
X318898D02*
X318098Y-38964D01*
X319698D01*
X318898Y-40564D01*
X324016Y-36627D02*
X323216Y-35027D01*
X324816D01*
X324016Y-36627D01*
X318898D02*
X318098Y-35027D01*
X319698D01*
X318898Y-36627D01*
X505118Y-24816D02*
X504318Y-23216D01*
X505918D01*
X505118Y-24816D01*
X500787Y-25210D02*
X499987Y-23609D01*
X501587D01*
X500787Y-25210D01*
X496457Y-24816D02*
X495657Y-23216D01*
X497257D01*
X496457Y-24816D01*
X505118Y-20879D02*
X504318Y-19279D01*
X505918D01*
X505118Y-20879D01*
X500787D02*
X499987Y-19279D01*
X501587D01*
X500787Y-20879D01*
X496457D02*
X495657Y-19279D01*
X497257D01*
X496457Y-20879D01*
X245669Y-74816D02*
X244869Y-73216D01*
X246469D01*
X245669Y-74816D01*
X246063Y-70879D02*
X245263Y-69279D01*
X246863D01*
X246063Y-70879D01*
X241732Y-74816D02*
X240932Y-73216D01*
X242532D01*
X241732Y-74816D01*
Y-70879D02*
X240932Y-69279D01*
X242532D01*
X241732Y-70879D01*
X326772Y-74422D02*
X325972Y-72822D01*
X327572D01*
X326772Y-74422D01*
X322441D02*
X321641Y-72822D01*
X323241D01*
X322441Y-74422D01*
X317717Y-74028D02*
X316916Y-72428D01*
X318516D01*
X317717Y-74028D01*
X326772Y-70091D02*
X325972Y-68491D01*
X327572D01*
X326772Y-70091D01*
X322441D02*
X321641Y-68491D01*
X323241D01*
X322441Y-70091D01*
X317717D02*
X316916Y-68491D01*
X318516D01*
X317717Y-70091D01*
X427953Y-206299D02*
Y-204966D01*
X428619Y-204300D01*
X429286Y-204966D01*
Y-206299D01*
Y-205299D01*
X427953D01*
X481496Y-197244D02*
Y-195911D01*
X482163Y-195245D01*
X482829Y-195911D01*
Y-197244D01*
Y-196244D01*
X481496D01*
X468504Y-45288D02*
X467704Y-43688D01*
X469304D01*
X468504Y-45288D01*
X463779D02*
X462980Y-43688D01*
X464579D01*
X463779Y-45288D01*
X458661Y-44894D02*
X457861Y-43295D01*
X459461D01*
X458661Y-44894D01*
X468898Y-40564D02*
X468098Y-38964D01*
X469698D01*
X468898Y-40564D01*
X463779Y-40170D02*
X462980Y-38570D01*
X464579D01*
X463779Y-40170D01*
X458661D02*
X457861Y-38570D01*
X459461D01*
X458661Y-40170D01*
X295669Y-46076D02*
X294869Y-44476D01*
X296469D01*
X295669Y-46076D01*
X290945D02*
X290145Y-44476D01*
X291745D01*
X290945Y-46076D01*
X295276Y-41745D02*
X294476Y-40145D01*
X296076D01*
X295276Y-41745D01*
X290945D02*
X290145Y-40145D01*
X291745D01*
X290945Y-41745D01*
X295276Y-36233D02*
X294476Y-34633D01*
X296076D01*
X295276Y-36233D01*
X290945D02*
X290145Y-34633D01*
X291745D01*
X290945Y-36233D01*
X118504Y-40945D02*
Y-39612D01*
X119170Y-38945D01*
X119837Y-39612D01*
Y-40945D01*
Y-39945D01*
X118504D01*
X85039Y-78359D02*
X84239Y-76759D01*
X85839D01*
X85039Y-78359D01*
X383465Y-234252D02*
Y-232919D01*
X384131Y-232253D01*
X384798Y-232919D01*
Y-234252D01*
Y-233252D01*
X383465D01*
X389764Y-234252D02*
Y-232919D01*
X390430Y-232253D01*
X391097Y-232919D01*
Y-234252D01*
Y-233252D01*
X389764D01*
X386614Y-237402D02*
Y-236069D01*
X387281Y-235402D01*
X387947Y-236069D01*
Y-237402D01*
Y-236402D01*
X386614D01*
Y-231102D02*
Y-229769D01*
X387281Y-229103D01*
X387947Y-229769D01*
Y-231102D01*
Y-230103D01*
X386614D01*
X611811Y-221260D02*
Y-219927D01*
X612477Y-219261D01*
X613144Y-219927D01*
Y-221260D01*
Y-220260D01*
X611811D01*
X426772Y-179528D02*
Y-178195D01*
X427438Y-177528D01*
X428105Y-178195D01*
Y-179528D01*
Y-178528D01*
X426772D01*
X418898Y-245276D02*
Y-243943D01*
X419564Y-243276D01*
X420230Y-243943D01*
Y-245276D01*
Y-244276D01*
X418898D01*
X602105Y-99109D02*
Y-97776D01*
X602771Y-97110D01*
X603438Y-97776D01*
Y-99109D01*
Y-98110D01*
X602105D01*
X597244Y-108661D02*
Y-107328D01*
X597910Y-106662D01*
X598577Y-107328D01*
Y-108661D01*
Y-107662D01*
X597244D01*
X592913Y-116535D02*
Y-115202D01*
X593580Y-114536D01*
X594246Y-115202D01*
Y-116535D01*
Y-115536D01*
X592913D01*
X594488Y-132677D02*
Y-131344D01*
X595155Y-130678D01*
X595821Y-131344D01*
Y-132677D01*
Y-131677D01*
X594488D01*
X43701Y-34646D02*
Y-33313D01*
X44367Y-32646D01*
X45034Y-33313D01*
Y-34646D01*
Y-33646D01*
X43701D01*
X51287Y-126878D02*
Y-125545D01*
X51954Y-124878D01*
X52620Y-125545D01*
Y-126878D01*
Y-125878D01*
X51287D01*
X13386Y-126878D02*
Y-125545D01*
X14052Y-124878D01*
X14719Y-125545D01*
Y-126878D01*
Y-125878D01*
X13386D01*
X29543Y-345214D02*
Y-343881D01*
X30209Y-343215D01*
X30876Y-343881D01*
Y-345214D01*
Y-344215D01*
X29543D01*
X240158Y-278740D02*
Y-277407D01*
X240824Y-276741D01*
X241490Y-277407D01*
Y-278740D01*
Y-277741D01*
X240158D01*
X26378Y-21272D02*
X25578Y-19672D01*
X27178D01*
X26378Y-21272D01*
X24409Y-17335D02*
X23609Y-15735D01*
X25210D01*
X24409Y-17335D01*
X26378Y-11430D02*
X25578Y-9830D01*
X27178D01*
X26378Y-11430D01*
X35433Y15354D02*
Y16687D01*
X36099Y17354D01*
X36766Y16687D01*
Y15354D01*
Y16354D01*
X35433D01*
X36220Y8268D02*
Y9601D01*
X36887Y10267D01*
X37553Y9601D01*
Y8268D01*
Y9267D01*
X36220D01*
X35827Y1575D02*
Y2908D01*
X36493Y3574D01*
X37160Y2908D01*
Y1575D01*
Y2575D01*
X35827D01*
X19685Y-2362D02*
Y-1029D01*
X20351Y-363D01*
X21018Y-1029D01*
Y-2362D01*
Y-1362D01*
X19685D01*
X20079Y3937D02*
Y5270D01*
X20745Y5936D01*
X21412Y5270D01*
Y3937D01*
Y4937D01*
X20079D01*
Y10630D02*
Y11963D01*
X20745Y12629D01*
X21412Y11963D01*
Y10630D01*
Y11630D01*
X20079D01*
Y17323D02*
Y18656D01*
X20745Y19322D01*
X21412Y18656D01*
Y17323D01*
Y18323D01*
X20079D01*
X298819Y-269685D02*
Y-268352D01*
X299485Y-267686D01*
X300152Y-268352D01*
Y-269685D01*
Y-268685D01*
X298819D01*
X391339Y-277953D02*
Y-276620D01*
X392005Y-275953D01*
X392671Y-276620D01*
Y-277953D01*
Y-276953D01*
X391339D01*
X299606Y-185433D02*
Y-184100D01*
X300273Y-183434D01*
X300939Y-184100D01*
Y-185433D01*
Y-184433D01*
X299606D01*
X231102Y-239764D02*
Y-238431D01*
X231769Y-237764D01*
X232435Y-238431D01*
Y-239764D01*
Y-238764D01*
X231102D01*
X230709Y-242913D02*
Y-241581D01*
X231375Y-240914D01*
X232042Y-241581D01*
Y-242913D01*
Y-241914D01*
X230709D01*
X399213Y-193307D02*
Y-191974D01*
X399879Y-191308D01*
X400546Y-191974D01*
Y-193307D01*
Y-192307D01*
X399213D01*
X204331Y-101575D02*
Y-100242D01*
X204997Y-99576D01*
X205664Y-100242D01*
Y-101575D01*
Y-100575D01*
X204331D01*
X432283Y-254724D02*
Y-253392D01*
X432950Y-252725D01*
X433616Y-253392D01*
Y-254724D01*
Y-253725D01*
X432283D01*
X496063Y-244094D02*
Y-242762D01*
X496729Y-242095D01*
X497396Y-242762D01*
Y-244094D01*
Y-243095D01*
X496063D01*
X173228Y-117323D02*
Y-115990D01*
X173895Y-115323D01*
X174561Y-115990D01*
Y-117323D01*
Y-116323D01*
X173228D01*
X261024Y-200394D02*
Y-199061D01*
X261690Y-198394D01*
X262356Y-199061D01*
Y-200394D01*
Y-199394D01*
X261024D01*
X381890Y-254331D02*
Y-252998D01*
X382556Y-252331D01*
X383223Y-252998D01*
Y-254331D01*
Y-253331D01*
X381890D01*
X318989Y-253024D02*
Y-251692D01*
X319655Y-251025D01*
X320322Y-251692D01*
Y-253024D01*
Y-252025D01*
X318989D01*
X337402Y-260630D02*
Y-259297D01*
X338068Y-258631D01*
X338735Y-259297D01*
Y-260630D01*
Y-259630D01*
X337402D01*
X429134Y-246850D02*
Y-245517D01*
X429800Y-244851D01*
X430467Y-245517D01*
Y-246850D01*
Y-245851D01*
X429134D01*
X483831Y-241339D02*
Y-240006D01*
X484498Y-239339D01*
X485164Y-240006D01*
Y-241339D01*
Y-240339D01*
X483831D01*
X488189Y-216535D02*
Y-215202D01*
X488855Y-214536D01*
X489522Y-215202D01*
Y-216535D01*
Y-215536D01*
X488189D01*
X500971Y-219896D02*
Y-218563D01*
X501637Y-217896D01*
X502304Y-218563D01*
Y-219896D01*
Y-218896D01*
X500971D01*
X470472Y-246457D02*
Y-245124D01*
X471139Y-244457D01*
X471805Y-245124D01*
Y-246457D01*
Y-245457D01*
X470472D01*
X476968Y-76378D02*
Y-75045D01*
X477635Y-74379D01*
X478301Y-75045D01*
Y-76378D01*
Y-75378D01*
X476968D01*
X462992Y-76378D02*
Y-75045D01*
X463659Y-74379D01*
X464325Y-75045D01*
Y-76378D01*
Y-75378D01*
X462992D01*
X289370Y-205906D02*
Y-204573D01*
X290037Y-203906D01*
X290703Y-204573D01*
Y-205906D01*
Y-204906D01*
X289370D01*
X343701Y-200394D02*
Y-199061D01*
X344367Y-198394D01*
X345034Y-199061D01*
Y-200394D01*
Y-199394D01*
X343701D01*
X357480Y-214567D02*
Y-213234D01*
X358147Y-212568D01*
X358813Y-213234D01*
Y-214567D01*
Y-213567D01*
X357480D01*
X153150Y-113386D02*
Y-112053D01*
X153816Y-111387D01*
X154482Y-112053D01*
Y-113386D01*
Y-112386D01*
X153150D01*
X226378Y-32677D02*
Y-31344D01*
X227044Y-30678D01*
X227711Y-31344D01*
Y-32677D01*
Y-31677D01*
X226378D01*
X100394Y-30315D02*
Y-28982D01*
X101060Y-28316D01*
X101727Y-28982D01*
Y-30315D01*
Y-29315D01*
X100394D01*
X383071Y-276772D02*
Y-275439D01*
X383737Y-274772D01*
X384404Y-275439D01*
Y-276772D01*
Y-275772D01*
X383071D01*
X402756Y-281102D02*
Y-279769D01*
X403422Y-279103D01*
X404089Y-279769D01*
Y-281102D01*
Y-280103D01*
X402756D01*
X616929Y-225984D02*
Y-224651D01*
X617596Y-223985D01*
X618262Y-224651D01*
Y-225984D01*
Y-224985D01*
X616929D01*
X611614Y-186107D02*
Y-184774D01*
X612281Y-184108D01*
X612947Y-184774D01*
Y-186107D01*
Y-185108D01*
X611614D01*
X586221Y-178740D02*
Y-177407D01*
X586887Y-176741D01*
X587553Y-177407D01*
Y-178740D01*
Y-177741D01*
X586221D01*
X591339Y-144488D02*
Y-143155D01*
X592005Y-142489D01*
X592671Y-143155D01*
Y-144488D01*
Y-143489D01*
X591339D01*
X586614Y-158661D02*
Y-157328D01*
X587281Y-156662D01*
X587947Y-157328D01*
Y-158661D01*
Y-157662D01*
X586614D01*
X582165Y-163898D02*
Y-162565D01*
X582832Y-161898D01*
X583498Y-162565D01*
Y-163898D01*
Y-162898D01*
X582165D01*
X581890Y-174016D02*
Y-172683D01*
X582556Y-172016D01*
X583223Y-172683D01*
Y-174016D01*
Y-173016D01*
X581890D01*
X579134Y-214006D02*
Y-212673D01*
X579800Y-212007D01*
X580467Y-212673D01*
Y-214006D01*
Y-213006D01*
X579134D01*
X581890Y-235925D02*
Y-234592D01*
X582556Y-233926D01*
X583223Y-234592D01*
Y-235925D01*
Y-234926D01*
X581890D01*
X584646Y-225197D02*
Y-223864D01*
X585312Y-223198D01*
X585979Y-223864D01*
Y-225197D01*
Y-224197D01*
X584646D01*
X590188Y-221161D02*
Y-219829D01*
X590855Y-219162D01*
X591521Y-219829D01*
Y-221161D01*
Y-220162D01*
X590188D01*
X608661Y-220472D02*
Y-219140D01*
X609328Y-218473D01*
X609994Y-219140D01*
Y-220472D01*
Y-219473D01*
X608661D01*
X589370Y-212992D02*
Y-211659D01*
X590036Y-210993D01*
X590703Y-211659D01*
Y-212992D01*
Y-211993D01*
X589370D01*
X588922Y-206462D02*
Y-205129D01*
X589589Y-204463D01*
X590255Y-205129D01*
Y-206462D01*
Y-205462D01*
X588922D01*
X583858Y-192913D02*
Y-191580D01*
X584525Y-190914D01*
X585191Y-191580D01*
Y-192913D01*
Y-191914D01*
X583858D01*
X589370Y-201575D02*
Y-200242D01*
X590036Y-199575D01*
X590703Y-200242D01*
Y-201575D01*
Y-200575D01*
X589370D01*
X329528Y-181890D02*
Y-180557D01*
X330194Y-179890D01*
X330860Y-180557D01*
Y-181890D01*
Y-180890D01*
X329528D01*
X307087Y-198819D02*
Y-197486D01*
X307753Y-196820D01*
X308419Y-197486D01*
Y-198819D01*
Y-197819D01*
X307087D01*
X279134Y-230315D02*
Y-228982D01*
X279800Y-228316D01*
X280467Y-228982D01*
Y-230315D01*
Y-229315D01*
X279134D01*
X280315Y-226378D02*
Y-225045D01*
X280981Y-224379D01*
X281648Y-225045D01*
Y-226378D01*
Y-225378D01*
X280315D01*
X277165Y-236221D02*
Y-234888D01*
X277832Y-234221D01*
X278498Y-234888D01*
Y-236221D01*
Y-235221D01*
X277165D01*
X281496Y-237402D02*
Y-236069D01*
X282162Y-235402D01*
X282829Y-236069D01*
Y-237402D01*
Y-236402D01*
X281496D01*
X27559Y-337402D02*
Y-336069D01*
X28225Y-335402D01*
X28892Y-336069D01*
Y-337402D01*
Y-336402D01*
X27559D01*
X288583Y-237402D02*
Y-236069D01*
X289249Y-235402D01*
X289916Y-236069D01*
Y-237402D01*
Y-236402D01*
X288583D01*
X293307Y-237008D02*
Y-235675D01*
X293973Y-235009D01*
X294640Y-235675D01*
Y-237008D01*
Y-236008D01*
X293307D01*
X341339Y-277953D02*
Y-276620D01*
X342005Y-275953D01*
X342671Y-276620D01*
Y-277953D01*
Y-276953D01*
X341339D01*
X407874Y-216535D02*
Y-215202D01*
X408540Y-214536D01*
X409207Y-215202D01*
Y-216535D01*
Y-215536D01*
X407874D01*
X408760Y-238189D02*
Y-236856D01*
X409426Y-236190D01*
X410093Y-236856D01*
Y-238189D01*
Y-237189D01*
X408760D01*
X462473Y-277635D02*
Y-276302D01*
X463140Y-275636D01*
X463806Y-276302D01*
Y-277635D01*
Y-276636D01*
X462473D01*
X321850Y-283465D02*
Y-282132D01*
X322517Y-281465D01*
X323183Y-282132D01*
Y-283465D01*
Y-282465D01*
X321850D01*
X461417Y-305118D02*
Y-303785D01*
X462084Y-303119D01*
X462750Y-303785D01*
Y-305118D01*
Y-304118D01*
X461417D01*
X343701Y-209449D02*
Y-208116D01*
X344367Y-207450D01*
X345034Y-208116D01*
Y-209449D01*
Y-208449D01*
X343701D01*
X347638Y-202756D02*
Y-201423D01*
X348304Y-200757D01*
X348971Y-201423D01*
Y-202756D01*
Y-201756D01*
X347638D01*
X383071Y-168110D02*
Y-166777D01*
X383737Y-166111D01*
X384404Y-166777D01*
Y-168110D01*
Y-167111D01*
X383071D01*
X598397Y-88288D02*
Y-86955D01*
X599063Y-86288D01*
X599730Y-86955D01*
Y-88288D01*
Y-87288D01*
X598397D01*
X603543Y-87795D02*
Y-86462D01*
X604210Y-85796D01*
X604876Y-86462D01*
Y-87795D01*
Y-86796D01*
X603543D01*
X135433Y-79134D02*
Y-77801D01*
X136100Y-77135D01*
X136766Y-77801D01*
Y-79134D01*
Y-78134D01*
X135433D01*
X424409Y-205512D02*
Y-204179D01*
X425076Y-203513D01*
X425742Y-204179D01*
Y-205512D01*
Y-204512D01*
X424409D01*
X428346Y-187795D02*
Y-186462D01*
X429013Y-185796D01*
X429679Y-186462D01*
Y-187795D01*
Y-186796D01*
X428346D01*
X140070Y-132385D02*
Y-131052D01*
X140736Y-130386D01*
X141402Y-131052D01*
Y-132385D01*
Y-131386D01*
X140070D01*
X140116Y-124048D02*
Y-122715D01*
X140783Y-122049D01*
X141449Y-122715D01*
Y-124048D01*
Y-123049D01*
X140116D01*
X141339Y394D02*
Y1727D01*
X142005Y2393D01*
X142672Y1727D01*
Y394D01*
Y1393D01*
X141339D01*
X180610Y-87795D02*
Y-86462D01*
X181277Y-85796D01*
X181943Y-86462D01*
Y-87795D01*
Y-86796D01*
X180610D01*
X198524Y-87795D02*
Y-86462D01*
X199190Y-85796D01*
X199856Y-86462D01*
Y-87795D01*
Y-86796D01*
X198524D01*
X197244Y-102756D02*
Y-101423D01*
X197910Y-100757D01*
X198577Y-101423D01*
Y-102756D01*
Y-101756D01*
X197244D01*
X181004Y-101181D02*
Y-99848D01*
X181670Y-99182D01*
X182337Y-99848D01*
Y-101181D01*
Y-100181D01*
X181004D01*
X177559Y-87795D02*
Y-86462D01*
X178226Y-85796D01*
X178892Y-86462D01*
Y-87795D01*
Y-86796D01*
X177559D01*
X197638Y-97638D02*
Y-96305D01*
X198304Y-95639D01*
X198971Y-96305D01*
Y-97638D01*
Y-96638D01*
X197638D01*
X182283Y-97244D02*
Y-95911D01*
X182950Y-95245D01*
X183616Y-95911D01*
Y-97244D01*
Y-96244D01*
X182283D01*
X182677Y-94488D02*
Y-93155D01*
X183344Y-92489D01*
X184010Y-93155D01*
Y-94488D01*
Y-93489D01*
X182677D01*
X189764Y-88189D02*
Y-86856D01*
X190430Y-86190D01*
X191097Y-86856D01*
Y-88189D01*
Y-87189D01*
X189764D01*
Y-100787D02*
Y-99454D01*
X190430Y-98788D01*
X191097Y-99454D01*
Y-100787D01*
Y-99788D01*
X189764D01*
X196850Y-94488D02*
Y-93155D01*
X197517Y-92489D01*
X198183Y-93155D01*
Y-94488D01*
Y-93489D01*
X196850D01*
X161417Y-25984D02*
Y-24651D01*
X162084Y-23985D01*
X162750Y-24651D01*
Y-25984D01*
Y-24985D01*
X161417D01*
X169291Y13386D02*
Y14719D01*
X169958Y15385D01*
X170624Y14719D01*
Y13386D01*
Y14386D01*
X169291D01*
Y9646D02*
Y10979D01*
X169958Y11645D01*
X170624Y10979D01*
Y9646D01*
Y10645D01*
X169291D01*
X159843Y9646D02*
Y10979D01*
X160509Y11645D01*
X161175Y10979D01*
Y9646D01*
Y10645D01*
X159843D01*
X151181Y14173D02*
Y15506D01*
X151848Y16173D01*
X152514Y15506D01*
Y14173D01*
Y15173D01*
X151181D01*
X142520Y13189D02*
Y14522D01*
X143186Y15188D01*
X143853Y14522D01*
Y13189D01*
Y14189D01*
X142520D01*
X144685Y-11811D02*
Y-10478D01*
X145352Y-9812D01*
X146018Y-10478D01*
Y-11811D01*
Y-10811D01*
X144685D01*
X162598Y-9449D02*
Y-8116D01*
X163265Y-7450D01*
X163931Y-8116D01*
Y-9449D01*
Y-8449D01*
X162598D01*
X153543Y-10433D02*
Y-9100D01*
X154210Y-8434D01*
X154876Y-9100D01*
Y-10433D01*
Y-9433D01*
X153543D01*
X162598Y-13189D02*
Y-11856D01*
X163265Y-11190D01*
X163931Y-11856D01*
Y-13189D01*
Y-12189D01*
X162598D01*
Y-1575D02*
Y-242D01*
X163265Y424D01*
X163931Y-242D01*
Y-1575D01*
Y-575D01*
X162598D01*
X151181Y18110D02*
Y19443D01*
X151848Y20110D01*
X152514Y19443D01*
Y18110D01*
Y19110D01*
X151181D01*
X137598Y-6299D02*
Y-4966D01*
X138265Y-4300D01*
X138931Y-4966D01*
Y-6299D01*
Y-5300D01*
X137598D01*
X134055Y-6299D02*
Y-4966D01*
X134722Y-4300D01*
X135388Y-4966D01*
Y-6299D01*
Y-5300D01*
X134055D01*
X149803Y-9238D02*
Y-7905D01*
X150470Y-7238D01*
X151136Y-7905D01*
Y-9238D01*
Y-8238D01*
X149803D01*
X150000Y-1587D02*
X149200Y13D01*
X150800D01*
X150000Y-1587D01*
X151782Y10443D02*
Y11776D01*
X152448Y12442D01*
X153115Y11776D01*
Y10443D01*
Y11443D01*
X151782D01*
X473303Y-276476D02*
Y-275144D01*
X473970Y-274477D01*
X474636Y-275144D01*
Y-276476D01*
Y-275477D01*
X473303D01*
X479331Y-294626D02*
Y-293293D01*
X479997Y-292627D01*
X480664Y-293293D01*
Y-294626D01*
Y-293627D01*
X479331D01*
X487402Y-256988D02*
Y-255655D01*
X488068Y-254989D01*
X488734Y-255655D01*
Y-256988D01*
Y-255989D01*
X487402D01*
X485827Y-279429D02*
Y-278096D01*
X486493Y-277430D01*
X487160Y-278096D01*
Y-279429D01*
Y-278430D01*
X485827D01*
X476772Y-254035D02*
Y-252702D01*
X477438Y-252036D01*
X478105Y-252702D01*
Y-254035D01*
Y-253036D01*
X476772D01*
X473622Y-259055D02*
Y-257722D01*
X474289Y-257056D01*
X474955Y-257722D01*
Y-259055D01*
Y-258055D01*
X473622D01*
X476378Y-273622D02*
Y-272289D01*
X477044Y-271623D01*
X477711Y-272289D01*
Y-273622D01*
Y-272622D01*
X476378D01*
X486221Y-265748D02*
Y-264415D01*
X486887Y-263749D01*
X487553Y-264415D01*
Y-265748D01*
Y-264748D01*
X486221D01*
X474409Y-265748D02*
Y-264415D01*
X475076Y-263749D01*
X475742Y-264415D01*
Y-265748D01*
Y-264748D01*
X474409D01*
X480315Y-259744D02*
Y-258411D01*
X480981Y-257745D01*
X481648Y-258411D01*
Y-259744D01*
Y-258744D01*
X480315D01*
Y-271752D02*
Y-270419D01*
X480981Y-269753D01*
X481648Y-270419D01*
Y-271752D01*
Y-270752D01*
X480315D01*
X548819Y-300787D02*
Y-299454D01*
X549485Y-298788D01*
X550152Y-299454D01*
Y-300787D01*
Y-299788D01*
X548819D01*
X489567Y-310236D02*
Y-308903D01*
X490233Y-308237D01*
X490900Y-308903D01*
Y-310236D01*
Y-309237D01*
X489567D01*
X492323Y-303543D02*
Y-302210D01*
X492989Y-301544D01*
X493656Y-302210D01*
Y-303543D01*
Y-302544D01*
X492323D01*
X495866Y-303543D02*
Y-302210D01*
X496533Y-301544D01*
X497199Y-302210D01*
Y-303543D01*
Y-302544D01*
X495866D01*
X483465Y-291535D02*
Y-290202D01*
X484131Y-289536D01*
X484797Y-290202D01*
Y-291535D01*
Y-290536D01*
X483465D01*
X476772Y-291929D02*
Y-290596D01*
X477438Y-289930D01*
X478105Y-290596D01*
Y-291929D01*
Y-290929D01*
X476772D01*
X466142Y-294685D02*
Y-293352D01*
X466808Y-292686D01*
X467475Y-293352D01*
Y-294685D01*
Y-293685D01*
X466142D01*
Y-298228D02*
Y-296895D01*
X466808Y-296229D01*
X467475Y-296895D01*
Y-298228D01*
Y-297229D01*
X466142D01*
X461417Y-312099D02*
Y-310766D01*
X462084Y-310099D01*
X462750Y-310766D01*
Y-312099D01*
Y-311099D01*
X461417D01*
X473819Y-315354D02*
Y-314021D01*
X474485Y-313355D01*
X475152Y-314021D01*
Y-315354D01*
Y-314355D01*
X473819D01*
X484842Y-317717D02*
Y-316384D01*
X485509Y-315717D01*
X486175Y-316384D01*
Y-317717D01*
Y-316717D01*
X484842D01*
X493110Y-310236D02*
Y-308903D01*
X493777Y-308237D01*
X494443Y-308903D01*
Y-310236D01*
Y-309237D01*
X493110D01*
X461024Y-302756D02*
Y-301423D01*
X461690Y-300757D01*
X462357Y-301423D01*
Y-302756D01*
Y-301756D01*
X461024D01*
X498425Y-307087D02*
Y-305754D01*
X499092Y-305087D01*
X499758Y-305754D01*
Y-307087D01*
Y-306087D01*
X498425D01*
X478346Y-305918D02*
X477547Y-304318D01*
X479146D01*
X478346Y-305918D01*
X477362Y-313767D02*
Y-312434D01*
X478029Y-311768D01*
X478695Y-312434D01*
Y-313767D01*
Y-312767D01*
X477362D01*
X596865Y-266396D02*
Y-265063D01*
X597531Y-264397D01*
X598197Y-265063D01*
Y-266396D01*
Y-265396D01*
X596865D01*
X594765Y-266396D02*
Y-265063D01*
X595431Y-264397D01*
X596097Y-265063D01*
Y-266396D01*
Y-265396D01*
X594765D01*
X624938Y-196373D02*
Y-195040D01*
X625604Y-194374D01*
X626271Y-195040D01*
Y-196373D01*
Y-195373D01*
X624938D01*
X624926Y-201353D02*
Y-200020D01*
X625593Y-199354D01*
X626259Y-200020D01*
Y-201353D01*
Y-200354D01*
X624926D01*
X624938Y-206373D02*
Y-205040D01*
X625604Y-204374D01*
X626271Y-205040D01*
Y-206373D01*
Y-205373D01*
X624938D01*
X624918Y-211353D02*
Y-210020D01*
X625585Y-209354D01*
X626251Y-210020D01*
Y-211353D01*
Y-210354D01*
X624918D01*
X625079Y-173898D02*
Y-172565D01*
X625745Y-171898D01*
X626412Y-172565D01*
Y-173898D01*
Y-172898D01*
X625079D01*
X624685Y-163898D02*
Y-162565D01*
X625351Y-161898D01*
X626018Y-162565D01*
Y-163898D01*
Y-162898D01*
X624685D01*
X551968Y-297638D02*
Y-296305D01*
X552635Y-295638D01*
X553301Y-296305D01*
Y-297638D01*
Y-296638D01*
X551968D01*
X127165Y-12598D02*
Y-11265D01*
X127832Y-10599D01*
X128498Y-11265D01*
Y-12598D01*
Y-11599D01*
X127165D01*
X118110Y-36220D02*
Y-34888D01*
X118777Y-34221D01*
X119443Y-34888D01*
Y-36220D01*
Y-35221D01*
X118110D01*
X117717Y-47293D02*
Y-45960D01*
X118383Y-45294D01*
X119049Y-45960D01*
Y-47293D01*
Y-46293D01*
X117717D01*
X121653Y-52756D02*
Y-51423D01*
X122320Y-50757D01*
X122986Y-51423D01*
Y-52756D01*
Y-51756D01*
X121653D01*
Y-31496D02*
Y-30163D01*
X122320Y-29497D01*
X122986Y-30163D01*
Y-31496D01*
Y-30496D01*
X121653D01*
X404493Y-224949D02*
X403693Y-223349D01*
X405293D01*
X404493Y-224949D01*
X404626Y-220485D02*
X403826Y-218885D01*
X405426D01*
X404626Y-220485D01*
X578332Y-261235D02*
Y-259902D01*
X578998Y-259236D01*
X579665Y-259902D01*
Y-261235D01*
Y-260235D01*
X578332D01*
X507874Y-255906D02*
Y-254573D01*
X508540Y-253906D01*
X509207Y-254573D01*
Y-255906D01*
Y-254906D01*
X507874D01*
X534814Y-297190D02*
Y-295857D01*
X535481Y-295191D01*
X536147Y-295857D01*
Y-297190D01*
Y-296191D01*
X534814D01*
X528960Y-296841D02*
Y-295508D01*
X529627Y-294841D01*
X530293Y-295508D01*
Y-296841D01*
Y-295841D01*
X528960D01*
X495276Y-298130D02*
Y-296797D01*
X495942Y-296131D01*
X496608Y-296797D01*
Y-298130D01*
Y-297130D01*
X495276D01*
X503346Y-297967D02*
Y-296634D01*
X504013Y-295967D01*
X504679Y-296634D01*
Y-297967D01*
Y-296967D01*
X503346D01*
X507480Y-298130D02*
Y-296797D01*
X508147Y-296131D01*
X508813Y-296797D01*
Y-298130D01*
Y-297130D01*
X507480D01*
X501181Y-298130D02*
Y-296797D01*
X501848Y-296131D01*
X502514Y-296797D01*
Y-298130D01*
Y-297130D01*
X501181D01*
X516929Y-298130D02*
Y-296797D01*
X517596Y-296131D01*
X518262Y-296797D01*
Y-298130D01*
Y-297130D01*
X516929D01*
X522835Y-297736D02*
Y-296403D01*
X523501Y-295737D01*
X524167Y-296403D01*
Y-297736D01*
Y-296737D01*
X522835D01*
X540945Y-297342D02*
Y-296010D01*
X541611Y-295343D01*
X542278Y-296010D01*
Y-297342D01*
Y-296343D01*
X540945D01*
X546457Y-297342D02*
Y-296010D01*
X547123Y-295343D01*
X547790Y-296010D01*
Y-297342D01*
Y-296343D01*
X546457D01*
X562205Y-297736D02*
Y-296403D01*
X562871Y-295737D01*
X563538Y-296403D01*
Y-297736D01*
Y-296737D01*
X562205D01*
X568110Y-297736D02*
Y-296403D01*
X568777Y-295737D01*
X569443Y-296403D01*
Y-297736D01*
Y-296737D01*
X568110D01*
X570472Y-297736D02*
Y-296403D01*
X571139Y-295737D01*
X571805Y-296403D01*
Y-297736D01*
Y-296737D01*
X570472D01*
X576378Y-297736D02*
Y-296403D01*
X577044Y-295737D01*
X577711Y-296403D01*
Y-297736D01*
Y-296737D01*
X576378D01*
X571260Y-256791D02*
Y-255458D01*
X571926Y-254792D01*
X572593Y-255458D01*
Y-256791D01*
Y-255792D01*
X571260D01*
X568898Y-256791D02*
Y-255458D01*
X569564Y-254792D01*
X570230Y-255458D01*
Y-256791D01*
Y-255792D01*
X568898D01*
X550000Y-255610D02*
Y-254277D01*
X550666Y-253611D01*
X551333Y-254277D01*
Y-255610D01*
Y-254611D01*
X550000D01*
X540945Y-256004D02*
Y-254671D01*
X541611Y-254005D01*
X542278Y-254671D01*
Y-256004D01*
Y-255004D01*
X540945D01*
X538976Y-250886D02*
Y-249553D01*
X539643Y-248886D01*
X540309Y-249553D01*
Y-250886D01*
Y-249886D01*
X538976D01*
X536614Y-245374D02*
Y-244041D01*
X537281Y-243375D01*
X537947Y-244041D01*
Y-245374D01*
Y-244374D01*
X536614D01*
X518110Y-255217D02*
Y-253884D01*
X518777Y-253217D01*
X519443Y-253884D01*
Y-255217D01*
Y-254217D01*
X518110D01*
X522047Y-249705D02*
Y-248372D01*
X522714Y-247705D01*
X523380Y-248372D01*
Y-249705D01*
Y-248705D01*
X522047D01*
X524016Y-243799D02*
Y-242466D01*
X524682Y-241800D01*
X525349Y-242466D01*
Y-243799D01*
Y-242799D01*
X524016D01*
X502362Y-257185D02*
Y-255852D01*
X503029Y-255186D01*
X503695Y-255852D01*
Y-257185D01*
Y-256185D01*
X502362D01*
X504331Y-257185D02*
Y-255852D01*
X504997Y-255186D01*
X505664Y-255852D01*
Y-257185D01*
Y-256185D01*
X504331D01*
X513386Y-254429D02*
Y-253096D01*
X514052Y-252430D01*
X514719Y-253096D01*
Y-254429D01*
Y-253429D01*
X513386D01*
X508268Y-251673D02*
Y-250340D01*
X508934Y-249674D01*
X509601Y-250340D01*
Y-251673D01*
Y-250674D01*
X508268D01*
X564173Y-255906D02*
Y-254573D01*
X564840Y-253906D01*
X565506Y-254573D01*
Y-255906D01*
Y-254906D01*
X564173D01*
X494882Y-262303D02*
Y-260970D01*
X495548Y-260304D01*
X496215Y-260970D01*
Y-262303D01*
Y-261303D01*
X494882D01*
X495669Y-255512D02*
Y-254179D01*
X496336Y-253513D01*
X497002Y-254179D01*
Y-255512D01*
Y-254512D01*
X495669D01*
X209449Y7087D02*
Y8420D01*
X210115Y9086D01*
X210782Y8420D01*
Y7087D01*
Y8086D01*
X209449D01*
X203937Y1969D02*
Y3301D01*
X204604Y3968D01*
X205270Y3301D01*
Y1969D01*
Y2968D01*
X203937D01*
X214173Y1181D02*
Y2514D01*
X214840Y3181D01*
X215506Y2514D01*
Y1181D01*
Y2181D01*
X214173D01*
Y-79134D02*
Y-77801D01*
X214840Y-77135D01*
X215506Y-77801D01*
Y-79134D01*
Y-78134D01*
X214173D01*
X205118Y-79380D02*
Y-78047D01*
X205785Y-77381D01*
X206451Y-78047D01*
Y-79380D01*
Y-78380D01*
X205118D01*
X214567Y-11417D02*
Y-10084D01*
X215233Y-9418D01*
X215900Y-10084D01*
Y-11417D01*
Y-10418D01*
X214567D01*
X211811Y-16535D02*
Y-15202D01*
X212477Y-14536D01*
X213144Y-15202D01*
Y-16535D01*
Y-15536D01*
X211811D01*
X209055Y-7480D02*
Y-6147D01*
X209722Y-5481D01*
X210388Y-6147D01*
Y-7480D01*
Y-6481D01*
X209055D01*
Y-5512D02*
Y-4179D01*
X209722Y-3512D01*
X210388Y-4179D01*
Y-5512D01*
Y-4512D01*
X209055D01*
X209449Y-3543D02*
Y-2210D01*
X210115Y-1544D01*
X210782Y-2210D01*
Y-3543D01*
Y-2544D01*
X209449D01*
X216535Y-25197D02*
Y-23864D01*
X217202Y-23198D01*
X217868Y-23864D01*
Y-25197D01*
Y-24197D01*
X216535D01*
X211024Y-21260D02*
Y-19927D01*
X211690Y-19261D01*
X212356Y-19927D01*
Y-21260D01*
Y-20260D01*
X211024D01*
X220866Y-39764D02*
Y-38431D01*
X221533Y-37764D01*
X222199Y-38431D01*
Y-39764D01*
Y-38764D01*
X220866D01*
X215354Y-42126D02*
Y-40793D01*
X216021Y-40127D01*
X216687Y-40793D01*
Y-42126D01*
Y-41126D01*
X215354D01*
X210236Y-44094D02*
Y-42762D01*
X210903Y-42095D01*
X211569Y-42762D01*
Y-44094D01*
Y-43095D01*
X210236D01*
X210630Y-53150D02*
Y-51817D01*
X211296Y-51150D01*
X211963Y-51817D01*
Y-53150D01*
Y-52150D01*
X210630D01*
X209541Y-58689D02*
Y-57356D01*
X210208Y-56690D01*
X210874Y-57356D01*
Y-58689D01*
Y-57689D01*
X209541D01*
X209449Y-72047D02*
Y-70714D01*
X210115Y-70048D01*
X210782Y-70714D01*
Y-72047D01*
Y-71048D01*
X209449D01*
Y-74410D02*
Y-73076D01*
X210115Y-72410D01*
X210782Y-73076D01*
Y-74410D01*
Y-73410D01*
X209449D01*
X168504Y-79528D02*
Y-78195D01*
X169170Y-77528D01*
X169837Y-78195D01*
Y-79528D01*
Y-78528D01*
X168504D01*
Y-73622D02*
Y-72289D01*
X169170Y-71623D01*
X169837Y-72289D01*
Y-73622D01*
Y-72622D01*
X168504D01*
Y-71260D02*
Y-69927D01*
X169170Y-69261D01*
X169837Y-69927D01*
Y-71260D01*
Y-70260D01*
X168504D01*
Y-65354D02*
Y-64021D01*
X169170Y-63355D01*
X169837Y-64021D01*
Y-65354D01*
Y-64355D01*
X168504D01*
X168898Y-49606D02*
Y-48273D01*
X169564Y-47607D01*
X170230Y-48273D01*
Y-49606D01*
Y-48607D01*
X168898D01*
Y-44094D02*
Y-42762D01*
X169564Y-42095D01*
X170230Y-42762D01*
Y-44094D01*
Y-43095D01*
X168898D01*
X168504Y-37795D02*
Y-36462D01*
X169170Y-35796D01*
X169837Y-36462D01*
Y-37795D01*
Y-36796D01*
X168504D01*
Y-31890D02*
Y-30557D01*
X169170Y-29890D01*
X169837Y-30557D01*
Y-31890D01*
Y-30890D01*
X168504D01*
Y-25984D02*
Y-24651D01*
X169170Y-23985D01*
X169837Y-24651D01*
Y-25984D01*
Y-24985D01*
X168504D01*
X168110Y-20079D02*
Y-18746D01*
X168777Y-18079D01*
X169443Y-18746D01*
Y-20079D01*
Y-19079D01*
X168110D01*
Y-4331D02*
Y-2998D01*
X168777Y-2331D01*
X169443Y-2998D01*
Y-4331D01*
Y-3331D01*
X168110D01*
Y-10630D02*
Y-9297D01*
X168777Y-8631D01*
X169443Y-9297D01*
Y-10630D01*
Y-9630D01*
X168110D01*
X168273Y-6496D02*
Y-5163D01*
X168940Y-4497D01*
X169606Y-5163D01*
Y-6496D01*
Y-5496D01*
X168273D01*
X168110Y1575D02*
Y2908D01*
X168777Y3574D01*
X169443Y2908D01*
Y1575D01*
Y2575D01*
X168110D01*
X101181Y-39383D02*
X100381Y-37783D01*
X101981D01*
X101181Y-39383D01*
X144095Y-80315D02*
Y-78982D01*
X144761Y-78316D01*
X145427Y-78982D01*
Y-80315D01*
Y-79315D01*
X144095D01*
X149606Y-80315D02*
Y-78982D01*
X150273Y-78316D01*
X150939Y-78982D01*
Y-80315D01*
Y-79315D01*
X149606D01*
X117323Y-65354D02*
Y-64021D01*
X117989Y-63355D01*
X118656Y-64021D01*
Y-65354D01*
Y-64355D01*
X117323D01*
X121467Y-74575D02*
Y-73242D01*
X122133Y-72575D01*
X122800Y-73242D01*
Y-74575D01*
Y-73575D01*
X121467D01*
X-18601Y-349409D02*
Y-348076D01*
X-17935Y-347410D01*
X-17268Y-348076D01*
Y-349409D01*
Y-348410D01*
X-18601D01*
X87795Y-99606D02*
Y-98273D01*
X88462Y-97607D01*
X89128Y-98273D01*
Y-99606D01*
Y-98607D01*
X87795D01*
X540551Y-340945D02*
Y-339612D01*
X541218Y-338946D01*
X541884Y-339612D01*
Y-340945D01*
Y-339945D01*
X540551D01*
X535827Y-345276D02*
Y-343943D01*
X536493Y-343276D01*
X537160Y-343943D01*
Y-345276D01*
Y-344276D01*
X535827D01*
X555512Y-340158D02*
Y-338825D01*
X556178Y-338158D01*
X556845Y-338825D01*
Y-340158D01*
Y-339158D01*
X555512D01*
X544882Y-336221D02*
Y-334888D01*
X545548Y-334221D01*
X546215Y-334888D01*
Y-336221D01*
Y-335221D01*
X544882D01*
X552756Y-335827D02*
Y-334494D01*
X553422Y-333827D01*
X554089Y-334494D01*
Y-335827D01*
Y-334827D01*
X552756D01*
X561024Y-340158D02*
Y-338825D01*
X561690Y-338158D01*
X562357Y-338825D01*
Y-340158D01*
Y-339158D01*
X561024D01*
X568898Y-319009D02*
Y-317676D01*
X569564Y-317010D01*
X570230Y-317676D01*
Y-319009D01*
Y-318010D01*
X568898D01*
X570079Y-309921D02*
Y-308588D01*
X570745Y-307921D01*
X571412Y-308588D01*
Y-309921D01*
Y-308921D01*
X570079D01*
X552756Y-305118D02*
Y-303785D01*
X553422Y-303119D01*
X554089Y-303785D01*
Y-305118D01*
Y-304118D01*
X552756D01*
X544882Y-305118D02*
Y-303785D01*
X545548Y-303119D01*
X546215Y-303785D01*
Y-305118D01*
Y-304118D01*
X544882D01*
X536221Y-300787D02*
Y-299454D01*
X536887Y-298788D01*
X537553Y-299454D01*
Y-300787D01*
Y-299788D01*
X536221D01*
X530709Y-300787D02*
Y-299454D01*
X531375Y-298788D01*
X532042Y-299454D01*
Y-300787D01*
Y-299788D01*
X530709D01*
X530315Y-338976D02*
Y-337644D01*
X530981Y-336977D01*
X531648Y-337644D01*
Y-338976D01*
Y-337977D01*
X530315D01*
X513406Y-302902D02*
Y-301570D01*
X514072Y-300903D01*
X514739Y-301570D01*
Y-302902D01*
Y-301903D01*
X513406D01*
X521654Y-336221D02*
Y-334888D01*
X522320Y-334221D01*
X522986Y-334888D01*
Y-336221D01*
Y-335221D01*
X521654D01*
X513386Y-336221D02*
Y-334888D01*
X514052Y-334221D01*
X514719Y-334888D01*
Y-336221D01*
Y-335221D01*
X513386D01*
X505410Y-336036D02*
Y-334703D01*
X506076Y-334037D01*
X506743Y-334703D01*
Y-336036D01*
Y-335037D01*
X505410D01*
X505512Y-303150D02*
Y-301817D01*
X506178Y-301150D01*
X506845Y-301817D01*
Y-303150D01*
Y-302150D01*
X505512D01*
X455118Y-93320D02*
X454318Y-91720D01*
X455918D01*
X455118Y-93320D01*
X460236Y-88595D02*
X459436Y-86995D01*
X461036D01*
X460236Y-88595D01*
Y-93320D02*
X459436Y-91720D01*
X461036D01*
X460236Y-93320D01*
X454724Y-88595D02*
X453924Y-86995D01*
X455524D01*
X454724Y-88595D01*
X624409Y-32296D02*
X623609Y-30696D01*
X625210D01*
X624409Y-32296D01*
X620079Y-32690D02*
X619279Y-31090D01*
X620879D01*
X620079Y-32690D01*
X615748Y-33084D02*
X614948Y-31484D01*
X616548D01*
X615748Y-33084D01*
X611417Y-33871D02*
X610617Y-32271D01*
X612217D01*
X611417Y-33871D01*
X620866Y-36627D02*
X620066Y-35027D01*
X621666D01*
X620866Y-36627D01*
X611811Y-38989D02*
X611011Y-37389D01*
X612611D01*
X611811Y-38989D01*
X601181Y-24422D02*
X600381Y-22822D01*
X601981D01*
X601181Y-24422D01*
X597244D02*
X596444Y-22822D01*
X598044D01*
X597244Y-24422D01*
Y-30721D02*
X596444Y-29121D01*
X598044D01*
X597244Y-30721D01*
X601181Y-27572D02*
X600381Y-25972D01*
X601981D01*
X601181Y-27572D01*
Y-30721D02*
X600381Y-29121D01*
X601981D01*
X601181Y-30721D01*
X597244Y-27572D02*
X596444Y-25972D01*
X598044D01*
X597244Y-27572D01*
X542913Y-73635D02*
X542113Y-72035D01*
X543713D01*
X542913Y-73635D01*
Y-70091D02*
X542113Y-68491D01*
X543713D01*
X542913Y-70091D01*
Y-66548D02*
X542113Y-64948D01*
X543713D01*
X542913Y-66548D01*
Y-62611D02*
X542113Y-61011D01*
X543713D01*
X542913Y-62611D01*
Y-59068D02*
X542113Y-57468D01*
X543713D01*
X542913Y-59068D01*
X595276Y-79921D02*
Y-78588D01*
X595942Y-77922D01*
X596608Y-78588D01*
Y-79921D01*
Y-78922D01*
X595276D01*
X608405Y-70079D02*
Y-68746D01*
X609072Y-68079D01*
X609738Y-68746D01*
Y-70079D01*
Y-69079D01*
X608405D01*
X618110Y-62205D02*
Y-60872D01*
X618777Y-60205D01*
X619443Y-60872D01*
Y-62205D01*
Y-61205D01*
X618110D01*
X616142Y-48438D02*
X615342Y-46838D01*
X616942D01*
X616142Y-48438D01*
X618898Y-51587D02*
X618098Y-49987D01*
X619698D01*
X618898Y-51587D01*
X613386D02*
X612586Y-49987D01*
X614186D01*
X613386Y-51587D01*
X609547Y-51981D02*
X608747Y-50381D01*
X610347D01*
X609547Y-51981D01*
X606693Y-51587D02*
X605893Y-49987D01*
X607493D01*
X606693Y-51587D01*
X601575Y-54343D02*
X600775Y-52743D01*
X602375D01*
X601575Y-54343D01*
X599213Y-50800D02*
X598413Y-49200D01*
X600013D01*
X599213Y-50800D01*
X544095Y-42926D02*
X543294Y-41326D01*
X544895D01*
X544095Y-42926D01*
X539764D02*
X538964Y-41326D01*
X540564D01*
X539764Y-42926D01*
X534646Y-52768D02*
X533846Y-51169D01*
X535446D01*
X534646Y-52768D01*
X534252Y-49225D02*
X533452Y-47625D01*
X535052D01*
X534252Y-49225D01*
X534646Y-46076D02*
X533846Y-44476D01*
X535446D01*
X534646Y-46076D01*
Y-42926D02*
X533846Y-41326D01*
X535446D01*
X534646Y-42926D01*
X238189Y-107087D02*
Y-105754D01*
X238855Y-105087D01*
X239522Y-105754D01*
Y-107087D01*
Y-106087D01*
X238189D01*
X233071Y-107087D02*
Y-105754D01*
X233737Y-105087D01*
X234404Y-105754D01*
Y-107087D01*
Y-106087D01*
X233071D01*
X223228Y-107480D02*
Y-106147D01*
X223895Y-105481D01*
X224561Y-106147D01*
Y-107480D01*
Y-106481D01*
X223228D01*
X228346Y-107480D02*
Y-106147D01*
X229013Y-105481D01*
X229679Y-106147D01*
Y-107480D01*
Y-106481D01*
X228346D01*
X238189Y-138976D02*
Y-137644D01*
X238855Y-136977D01*
X239522Y-137644D01*
Y-138976D01*
Y-137977D01*
X238189D01*
X233209Y-139232D02*
Y-137899D01*
X233875Y-137233D01*
X234542Y-137899D01*
Y-139232D01*
Y-138233D01*
X233209D01*
X228209Y-138721D02*
Y-137388D01*
X228875Y-136721D01*
X229542Y-137388D01*
Y-138721D01*
Y-137721D01*
X228209D01*
X217405Y-138189D02*
Y-136856D01*
X218072Y-136190D01*
X218738Y-136856D01*
Y-138189D01*
Y-137189D01*
X217405D01*
X223209Y-137815D02*
Y-136482D01*
X223875Y-135816D01*
X224542Y-136482D01*
Y-137815D01*
Y-136815D01*
X223209D01*
X214173Y-107087D02*
Y-105754D01*
X214840Y-105087D01*
X215506Y-105754D01*
Y-107087D01*
Y-106087D01*
X214173D01*
X192126Y-111811D02*
Y-110478D01*
X192792Y-109812D01*
X193459Y-110478D01*
Y-111811D01*
Y-110811D01*
X192126D01*
X199193Y-105925D02*
Y-104592D01*
X199859Y-103926D01*
X200526Y-104592D01*
Y-105925D01*
Y-104925D01*
X199193D01*
X204193Y-138257D02*
Y-136924D01*
X204859Y-136258D01*
X205526Y-136924D01*
Y-138257D01*
Y-137257D01*
X204193D01*
X199193Y-138680D02*
Y-137347D01*
X199859Y-136680D01*
X200526Y-137347D01*
Y-138680D01*
Y-137680D01*
X199193D01*
X130245Y-120870D02*
Y-119537D01*
X130911Y-118870D01*
X131577Y-119537D01*
Y-120870D01*
Y-119870D01*
X130245D01*
X133099Y-119984D02*
Y-118651D01*
X133765Y-117984D01*
X134432Y-118651D01*
Y-119984D01*
Y-118984D01*
X133099D01*
X148425Y-104336D02*
Y-103003D01*
X149092Y-102336D01*
X149758Y-103003D01*
Y-104336D01*
Y-103336D01*
X148425D01*
X153150Y-103412D02*
Y-102079D01*
X153816Y-101412D01*
X154482Y-102079D01*
Y-103412D01*
Y-102412D01*
X153150D01*
Y-99691D02*
Y-98358D01*
X153816Y-97691D01*
X154482Y-98358D01*
Y-99691D01*
Y-98691D01*
X153150D01*
X158268Y-107480D02*
Y-106147D01*
X158934Y-105481D01*
X159601Y-106147D01*
Y-107480D01*
Y-106481D01*
X158268D01*
X168110Y-103937D02*
Y-102604D01*
X168777Y-101938D01*
X169443Y-102604D01*
Y-103937D01*
Y-102937D01*
X168110D01*
Y-100132D02*
Y-98799D01*
X168777Y-98132D01*
X169443Y-98799D01*
Y-100132D01*
Y-99132D01*
X168110D01*
X161417Y-95276D02*
Y-93943D01*
X162084Y-93276D01*
X162750Y-93943D01*
Y-95276D01*
Y-94276D01*
X161417D01*
Y-107480D02*
Y-106147D01*
X162084Y-105481D01*
X162750Y-106147D01*
Y-107480D01*
Y-106481D01*
X161417D01*
X126592Y-94557D02*
X127392Y-93757D01*
X128192Y-94557D01*
X127392Y-95357D01*
X126592Y-94557D01*
X364781Y7806D02*
X365581Y8606D01*
X366381Y7806D01*
X365581Y7006D01*
X364781Y7806D01*
Y-94557D02*
X365581Y-93757D01*
X366381Y-94557D01*
X365581Y-95357D01*
X364781Y-94557D01*
X126592Y7806D02*
X127392Y8606D01*
X128192Y7806D01*
X127392Y7006D01*
X126592Y7806D01*
X178185Y-136811D02*
Y-135478D01*
X178852Y-134812D01*
X179518Y-135478D01*
Y-136811D01*
Y-135811D01*
X178185D01*
Y-133661D02*
Y-132328D01*
X178852Y-131662D01*
X179518Y-132328D01*
Y-133661D01*
Y-132662D01*
X178185D01*
X150627Y-130512D02*
Y-129179D01*
X151293Y-128513D01*
X151959Y-129179D01*
Y-130512D01*
Y-129512D01*
X150627D01*
X150233Y-127362D02*
Y-126029D01*
X150899Y-125363D01*
X151566Y-126029D01*
Y-127362D01*
Y-126363D01*
X150233D01*
X152904Y-124213D02*
Y-122880D01*
X153571Y-122213D01*
X154237Y-122880D01*
Y-124213D01*
Y-123213D01*
X152904D01*
X152398Y-117717D02*
Y-116384D01*
X153065Y-115717D01*
X153731Y-116384D01*
Y-117717D01*
Y-116717D01*
X152398D01*
X156926Y-111614D02*
Y-110281D01*
X157592Y-109615D01*
X158259Y-110281D01*
Y-111614D01*
Y-110615D01*
X156926D01*
X164843Y-114040D02*
Y-112707D01*
X165509Y-112040D01*
X166176Y-112707D01*
Y-114040D01*
Y-113040D01*
X164843D01*
X160075Y-112402D02*
Y-111069D01*
X160742Y-110402D01*
X161408Y-111069D01*
Y-112402D01*
Y-111402D01*
X160075D01*
X168343Y-110827D02*
Y-109494D01*
X169009Y-108827D01*
X169676Y-109494D01*
Y-110827D01*
Y-109827D01*
X168343D01*
X186847Y-135236D02*
Y-133903D01*
X187513Y-133237D01*
X188180Y-133903D01*
Y-135236D01*
Y-134237D01*
X186847D01*
X188028Y-113583D02*
Y-112250D01*
X188695Y-111583D01*
X189361Y-112250D01*
Y-113583D01*
Y-112583D01*
X188028D01*
X189209Y-132139D02*
X188409Y-130539D01*
X190009D01*
X189209Y-132139D01*
Y-118280D02*
X188409Y-116680D01*
X190009D01*
X189209Y-118280D01*
X173461Y-127362D02*
Y-126029D01*
X174128Y-125363D01*
X174794Y-126029D01*
Y-127362D01*
Y-126363D01*
X173461D01*
X165587Y-139961D02*
Y-138628D01*
X166253Y-137961D01*
X166920Y-138628D01*
Y-139961D01*
Y-138961D01*
X165587D01*
X151808Y-137205D02*
Y-135872D01*
X152474Y-135205D01*
X153140Y-135872D01*
Y-137205D01*
Y-136205D01*
X151808D01*
X162241Y-140004D02*
Y-138671D01*
X162907Y-138005D01*
X163574Y-138671D01*
Y-140004D01*
Y-139004D01*
X162241D01*
X106693Y14554D02*
X105893Y16154D01*
X107493D01*
X106693Y14554D01*
X107087Y8649D02*
X106287Y10249D01*
X107887D01*
X107087Y8649D01*
X111024D02*
X110224Y10249D01*
X111824D01*
X111024Y8649D01*
Y14554D02*
X110224Y16154D01*
X111824D01*
X111024Y14554D01*
X105512Y-80721D02*
X104712Y-79121D01*
X106312D01*
X105512Y-80721D01*
X109843D02*
X109043Y-79121D01*
X110643D01*
X109843Y-80721D01*
Y-75209D02*
X109043Y-73610D01*
X110643D01*
X109843Y-75209D01*
X105512D02*
X104712Y-73610D01*
X106312D01*
X105512Y-75209D01*
X99606Y-64579D02*
X98806Y-62980D01*
X100406D01*
X99606Y-64579D01*
X107874D02*
X107074Y-62980D01*
X108674D01*
X107874Y-64579D01*
Y-60642D02*
X107074Y-59043D01*
X108674D01*
X107874Y-60642D01*
X99606D02*
X98806Y-59043D01*
X100406D01*
X99606Y-60642D01*
X74616Y-62523D02*
X73816Y-60923D01*
X75415D01*
X74616Y-62523D01*
X56693Y1060D02*
Y2392D01*
X57359Y3059D01*
X58026Y2392D01*
Y1060D01*
Y2059D01*
X56693D01*
X39764Y-30328D02*
X38964Y-28728D01*
X40564D01*
X39764Y-30328D01*
Y-26784D02*
X38964Y-25184D01*
X40564D01*
X39764Y-26784D01*
X35731Y-10643D02*
X34931Y-9042D01*
X36531D01*
X35731Y-10643D01*
Y-19698D02*
X34931Y-18098D01*
X36531D01*
X35731Y-19698D01*
X47441Y-28162D02*
X46641Y-26562D01*
X48241D01*
X47441Y-28162D01*
Y-22060D02*
X46641Y-20460D01*
X48241D01*
X47441Y-22060D01*
Y-6509D02*
X46641Y-4909D01*
X48241D01*
X47441Y-6509D01*
Y-12611D02*
X46641Y-11011D01*
X48241D01*
X47441Y-12611D01*
X75394Y-6509D02*
X74594Y-4909D01*
X76194D01*
X75394Y-6509D01*
Y-12611D02*
X74594Y-11011D01*
X76194D01*
X75394Y-12611D01*
X66142D02*
X65342Y-11011D01*
X66942D01*
X66142Y-12611D01*
X61417D02*
X60617Y-11011D01*
X62217D01*
X61417Y-12611D01*
X56693D02*
X55893Y-11011D01*
X57493D01*
X56693Y-12611D01*
Y-17335D02*
X55893Y-15735D01*
X57493D01*
X56693Y-17335D01*
X61417D02*
X60617Y-15735D01*
X62217D01*
X61417Y-17335D01*
X66142D02*
X65342Y-15735D01*
X66942D01*
X66142Y-17335D01*
Y-22060D02*
X65342Y-20460D01*
X66942D01*
X66142Y-22060D01*
X61417D02*
X60617Y-20460D01*
X62217D01*
X61417Y-22060D01*
X52362Y-35531D02*
Y-34199D01*
X53029Y-33532D01*
X53695Y-34199D01*
Y-35531D01*
Y-34532D01*
X52362D01*
X61417Y-35741D02*
Y-34408D01*
X62084Y-33741D01*
X62750Y-34408D01*
Y-35741D01*
Y-34741D01*
X61417D01*
X37402Y-43355D02*
Y-42022D01*
X38068Y-41356D01*
X38734Y-42022D01*
Y-43355D01*
Y-42356D01*
X37402D01*
X38382Y-48355D02*
Y-47023D01*
X39048Y-46356D01*
X39715Y-47023D01*
Y-48355D01*
Y-47356D01*
X38382D01*
X66102Y-64085D02*
Y-62752D01*
X66769Y-62085D01*
X67435Y-62752D01*
Y-64085D01*
Y-63085D01*
X66102D01*
X72795Y-53355D02*
Y-52022D01*
X73461Y-51356D01*
X74127Y-52022D01*
Y-53355D01*
Y-52356D01*
X72795D01*
X86614Y-57099D02*
X85814Y-55499D01*
X87414D01*
X86614Y-57099D01*
X91339Y-35839D02*
X90539Y-34239D01*
X92139D01*
X91339Y-35839D01*
X86614Y-40170D02*
X85814Y-38570D01*
X87414D01*
X86614Y-40170D01*
X88583Y-54737D02*
X87783Y-53137D01*
X89383D01*
X88583Y-54737D01*
X85039D02*
X84239Y-53137D01*
X85839D01*
X85039Y-54737D01*
X88583Y-51587D02*
X87783Y-49987D01*
X89383D01*
X88583Y-51587D01*
X85039D02*
X84239Y-49987D01*
X85839D01*
X85039Y-51587D01*
X88583Y-47257D02*
X87783Y-45657D01*
X89383D01*
X88583Y-47257D01*
X85039Y-47650D02*
X84239Y-46050D01*
X85839D01*
X85039Y-47650D01*
X84252Y-9855D02*
X83452Y-8255D01*
X85052D01*
X84252Y-9855D01*
Y-6706D02*
X83452Y-5105D01*
X85052D01*
X84252Y-6706D01*
Y-3162D02*
X83452Y-1562D01*
X85052D01*
X84252Y-3162D01*
X88257Y-3300D02*
X87458Y-1700D01*
X89057D01*
X88257Y-3300D01*
X93608Y-4180D02*
X92808Y-2579D01*
X94408D01*
X93608Y-4180D01*
X90158Y-8280D02*
X89358Y-6680D01*
X90957D01*
X90158Y-8280D01*
X107832Y-10997D02*
X107032Y-9397D01*
X108632D01*
X107832Y-10997D01*
X97408D02*
X96608Y-9397D01*
X98208D01*
X97408Y-10997D01*
X106693Y-28359D02*
X105893Y-26759D01*
X107493D01*
X106693Y-28359D01*
X105282Y-20091D02*
X104482Y-18491D01*
X106082D01*
X105282Y-20091D01*
X85827Y-16929D02*
Y-15596D01*
X86493Y-14930D01*
X87160Y-15596D01*
Y-16929D01*
Y-15929D01*
X85827D01*
X85853Y-13780D02*
Y-12447D01*
X86520Y-11780D01*
X87186Y-12447D01*
Y-13780D01*
Y-12780D01*
X85853D01*
X78740Y17310D02*
X77940Y18910D01*
X79540D01*
X78740Y17310D01*
Y14554D02*
X77940Y16154D01*
X79540D01*
X78740Y14554D01*
Y9042D02*
X77940Y10643D01*
X79540D01*
X78740Y9042D01*
Y5893D02*
X77940Y7493D01*
X79540D01*
X78740Y5893D01*
Y2743D02*
X77940Y4343D01*
X79540D01*
X78740Y2743D01*
X110589Y789D02*
X109789Y2389D01*
X111389D01*
X110589Y789D01*
X108268Y-406D02*
X107468Y1194D01*
X109068D01*
X108268Y-406D01*
X112598D02*
X111798Y1194D01*
X113398D01*
X112598Y-406D01*
X116929Y-21654D02*
Y-20321D01*
X117596Y-19654D01*
X118262Y-20321D01*
Y-21654D01*
Y-20654D01*
X116929D01*
X118898Y-16929D02*
Y-15596D01*
X119564Y-14930D01*
X120230Y-15596D01*
Y-16929D01*
Y-15929D01*
X118898D01*
X366043Y-153937D02*
Y-152604D01*
X366710Y-151938D01*
X367376Y-152604D01*
Y-153937D01*
Y-152937D01*
X366043D01*
X373228Y-162598D02*
Y-161266D01*
X373895Y-160599D01*
X374561Y-161266D01*
Y-162598D01*
Y-161599D01*
X373228D01*
X378346Y-161811D02*
Y-160478D01*
X379013Y-159812D01*
X379679Y-160478D01*
Y-161811D01*
Y-160811D01*
X378346D01*
X388713Y-128731D02*
Y-127398D01*
X389379Y-126732D01*
X390045Y-127398D01*
Y-128731D01*
Y-127731D01*
X388713D01*
X383083Y-128504D02*
Y-127171D01*
X383749Y-126505D01*
X384416Y-127171D01*
Y-128504D01*
Y-127504D01*
X383083D01*
X336221Y-122847D02*
X335420Y-121247D01*
X337020D01*
X336221Y-122847D01*
X333465D02*
X332665Y-121247D01*
X334265D01*
X333465Y-122847D01*
X330315Y-122453D02*
X329515Y-120853D01*
X331115D01*
X330315Y-122453D01*
X335827Y-164973D02*
X335027Y-163373D01*
X336627D01*
X335827Y-164973D01*
X333071D02*
X332271Y-163373D01*
X333871D01*
X333071Y-164973D01*
X329919Y-164808D02*
X329118Y-163208D01*
X330718D01*
X329919Y-164808D01*
X329656Y-143280D02*
X328856Y-141680D01*
X330456D01*
X329656Y-143280D01*
X329722Y-146627D02*
X328922Y-145027D01*
X330522D01*
X329722Y-146627D01*
X347638Y-119882D02*
Y-118549D01*
X348304Y-117883D01*
X348971Y-118549D01*
Y-119882D01*
Y-118882D01*
X347638D01*
X347244Y-113189D02*
Y-111856D01*
X347910Y-111190D01*
X348577Y-111856D01*
Y-113189D01*
Y-112189D01*
X347244D01*
X355035Y-105876D02*
Y-104543D01*
X355701Y-103876D01*
X356368Y-104543D01*
Y-105876D01*
Y-104876D01*
X355035D01*
X390654Y-104510D02*
Y-103177D01*
X391320Y-102510D01*
X391987Y-103177D01*
Y-104510D01*
Y-103510D01*
X390654D01*
X383465Y-103543D02*
Y-102210D01*
X384131Y-101544D01*
X384798Y-102210D01*
Y-103543D01*
Y-102544D01*
X383465D01*
X369685Y-124422D02*
X368885Y-122822D01*
X370485D01*
X369685Y-124422D01*
Y-121666D02*
X368885Y-120066D01*
X370485D01*
X369685Y-121666D01*
Y-118910D02*
X368885Y-117310D01*
X370485D01*
X369685Y-118910D01*
X366929Y-124422D02*
X366129Y-122822D01*
X367729D01*
X366929Y-124422D01*
Y-121666D02*
X366129Y-120066D01*
X367729D01*
X366929Y-121666D01*
X363779Y-124422D02*
X362980Y-122822D01*
X364580D01*
X363779Y-124422D01*
X366929Y-118910D02*
X366129Y-117310D01*
X367729D01*
X366929Y-118910D01*
X363779Y-121666D02*
X362980Y-120066D01*
X364580D01*
X363779Y-121666D01*
Y-118910D02*
X362980Y-117310D01*
X364580D01*
X363779Y-118910D01*
X448425Y-166154D02*
X447625Y-164554D01*
X449225D01*
X448425Y-166154D01*
X451968D02*
X451168Y-164554D01*
X452769D01*
X451968Y-166154D01*
X455512D02*
X454712Y-164554D01*
X456312D01*
X455512Y-166154D01*
X458661D02*
X457861Y-164554D01*
X459461D01*
X458661Y-166154D01*
X442815Y-162547D02*
X442015Y-160947D01*
X443615D01*
X442815Y-162547D01*
Y-166647D02*
X442015Y-165047D01*
X443615D01*
X442815Y-166647D01*
X439561D02*
X438761Y-165047D01*
X440361D01*
X439561Y-166647D01*
X425984Y-110643D02*
X425184Y-109043D01*
X426784D01*
X425984Y-110643D01*
X425630Y-113694D02*
X424830Y-112094D01*
X426430D01*
X425630Y-113694D01*
X416535Y-121568D02*
X415735Y-119968D01*
X417335D01*
X416535Y-121568D01*
X423622Y-116154D02*
X422822Y-114554D01*
X424422D01*
X423622Y-116154D01*
X436811Y-154343D02*
X436011Y-152743D01*
X437611D01*
X436811Y-154343D01*
X418110D02*
X417310Y-152743D01*
X418910D01*
X418110Y-154343D01*
X422835D02*
X422035Y-152743D01*
X423635D01*
X422835Y-154343D01*
X427559D02*
X426759Y-152743D01*
X428359D01*
X427559Y-154343D01*
Y-149619D02*
X426759Y-148019D01*
X428359D01*
X427559Y-149619D01*
X418110D02*
X417310Y-148019D01*
X418910D01*
X418110Y-149619D01*
X422835D02*
X422035Y-148019D01*
X423635D01*
X422835Y-149619D01*
Y-144895D02*
X422035Y-143295D01*
X423635D01*
X422835Y-144895D01*
X418110D02*
X417310Y-143295D01*
X418910D01*
X418110Y-144895D01*
X422835Y-131791D02*
Y-130458D01*
X423501Y-129792D01*
X424168Y-130458D01*
Y-131791D01*
Y-130792D01*
X422835D01*
X427843Y-166966D02*
Y-165633D01*
X428510Y-164967D01*
X429176Y-165633D01*
Y-166966D01*
Y-165967D01*
X427843D01*
X422835Y-166284D02*
Y-164951D01*
X423501Y-164285D01*
X424168Y-164951D01*
Y-166284D01*
Y-165285D01*
X422835D01*
X406693Y-126784D02*
X405893Y-125184D01*
X407493D01*
X406693Y-126784D01*
X408268Y-125209D02*
X407468Y-123609D01*
X409068D01*
X408268Y-125209D01*
Y-122847D02*
X407468Y-121247D01*
X409068D01*
X408268Y-122847D01*
X400984Y-127102D02*
Y-125769D01*
X401651Y-125103D01*
X402317Y-125769D01*
Y-127102D01*
Y-126102D01*
X400984D01*
X415748Y-129609D02*
Y-128276D01*
X416414Y-127610D01*
X417081Y-128276D01*
Y-129609D01*
Y-128609D01*
X415748D01*
X418898Y-129753D02*
Y-128420D01*
X419564Y-127754D01*
X420230Y-128420D01*
Y-129753D01*
Y-128754D01*
X418898D01*
X445276Y-104343D02*
X444476Y-102743D01*
X446076D01*
X445276Y-104343D01*
X444488Y-107099D02*
X443688Y-105499D01*
X445288D01*
X444488Y-107099D01*
X440945Y-106705D02*
X440145Y-105105D01*
X441745D01*
X440945Y-106705D01*
X436221Y-107099D02*
X435421Y-105499D01*
X437020D01*
X436221Y-107099D01*
X434347Y-104543D02*
X433547Y-102943D01*
X435147D01*
X434347Y-104543D01*
X434646Y-101587D02*
X433846Y-99987D01*
X435446D01*
X434646Y-101587D01*
X431496Y-100800D02*
X430696Y-99200D01*
X432296D01*
X431496Y-100800D01*
X422047Y-101969D02*
Y-100636D01*
X422714Y-99969D01*
X423380Y-100636D01*
Y-101969D01*
Y-100969D01*
X422047D01*
X418898Y-100000D02*
Y-98667D01*
X419564Y-98001D01*
X420230Y-98667D01*
Y-100000D01*
Y-99000D01*
X418898D01*
X445669Y-129147D02*
X444869Y-127547D01*
X446469D01*
X445669Y-129147D01*
X449606D02*
X448806Y-127547D01*
X450406D01*
X449606Y-129147D01*
Y-125603D02*
X448806Y-124003D01*
X450406D01*
X449606Y-125603D01*
Y-122453D02*
X448806Y-120853D01*
X450406D01*
X449606Y-122453D01*
X275590Y-199606D02*
Y-198273D01*
X276257Y-197607D01*
X276923Y-198273D01*
Y-199606D01*
Y-198607D01*
X275590D01*
X289370Y-200394D02*
Y-199061D01*
X290037Y-198394D01*
X290703Y-199061D01*
Y-200394D01*
Y-199394D01*
X289370D01*
X274803Y-188583D02*
Y-187250D01*
X275470Y-186583D01*
X276136Y-187250D01*
Y-188583D01*
Y-187583D01*
X274803D01*
X291831Y-197012D02*
Y-195679D01*
X292497Y-195013D01*
X293164Y-195679D01*
Y-197012D01*
Y-196013D01*
X291831D01*
X295669Y-191339D02*
Y-190006D01*
X296336Y-189339D01*
X297002Y-190006D01*
Y-191339D01*
Y-190339D01*
X295669D01*
X292815Y-187106D02*
Y-185773D01*
X293481Y-185107D01*
X294148Y-185773D01*
Y-187106D01*
Y-186107D01*
X292815D01*
X275590Y-184252D02*
Y-182919D01*
X276257Y-182253D01*
X276923Y-182919D01*
Y-184252D01*
Y-183252D01*
X275590D01*
X281890Y-188583D02*
Y-187250D01*
X282556Y-186583D01*
X283223Y-187250D01*
Y-188583D01*
Y-187583D01*
X281890D01*
Y-200771D02*
Y-199438D01*
X282556Y-198772D01*
X283223Y-199438D01*
Y-200771D01*
Y-199772D01*
X281890D01*
X288583Y-195276D02*
Y-193943D01*
X289249Y-193276D01*
X289916Y-193943D01*
Y-195276D01*
Y-194276D01*
X288583D01*
X275503Y-195276D02*
Y-193943D01*
X276170Y-193276D01*
X276836Y-193943D01*
Y-195276D01*
Y-194276D01*
X275503D01*
X596063Y-239895D02*
Y-238562D01*
X596729Y-237895D01*
X597396Y-238562D01*
Y-239895D01*
Y-238895D01*
X596063D01*
Y-241995D02*
Y-240662D01*
X596729Y-239996D01*
X597396Y-240662D01*
Y-241995D01*
Y-240995D01*
X596063D01*
X321654Y-232677D02*
Y-231344D01*
X322320Y-230678D01*
X322986Y-231344D01*
Y-232677D01*
Y-231678D01*
X321654D01*
X336614Y-286221D02*
Y-284888D01*
X337281Y-284221D01*
X337947Y-284888D01*
Y-286221D01*
Y-285221D01*
X336614D01*
X315945Y-287795D02*
Y-286462D01*
X316611Y-285796D01*
X317278Y-286462D01*
Y-287795D01*
Y-286796D01*
X315945D01*
X315333Y-299430D02*
Y-298097D01*
X316000Y-297431D01*
X316666Y-298097D01*
Y-299430D01*
Y-298431D01*
X315333D01*
X336811Y-299399D02*
Y-298066D01*
X337477Y-297399D01*
X338144Y-298066D01*
Y-299399D01*
Y-298399D01*
X336811D01*
X313386Y-283465D02*
Y-282132D01*
X314052Y-281465D01*
X314719Y-282132D01*
Y-283465D01*
Y-282465D01*
X313386D01*
X308268Y-300000D02*
Y-298667D01*
X308934Y-298001D01*
X309601Y-298667D01*
Y-300000D01*
Y-299000D01*
X308268D01*
X324184Y-302194D02*
Y-300861D01*
X324851Y-300194D01*
X325517Y-300861D01*
Y-302194D01*
Y-301194D01*
X324184D01*
X356693Y-288583D02*
Y-287250D01*
X357359Y-286583D01*
X358026Y-287250D01*
Y-288583D01*
Y-287583D01*
X356693D01*
X355741Y-296063D02*
Y-294730D01*
X356407Y-294064D01*
X357074Y-294730D01*
Y-296063D01*
Y-295063D01*
X355741D01*
X314961Y-293701D02*
Y-292368D01*
X315627Y-291701D01*
X316294Y-292368D01*
Y-293701D01*
Y-292701D01*
X314961D01*
X320472Y-299569D02*
Y-298236D01*
X321139Y-297570D01*
X321805Y-298236D01*
Y-299569D01*
Y-298570D01*
X320472D01*
X325776Y-293701D02*
Y-292368D01*
X326443Y-291701D01*
X327109Y-292368D01*
Y-293701D01*
Y-292701D01*
X325776D01*
X320472Y-287865D02*
Y-286532D01*
X321139Y-285865D01*
X321805Y-286532D01*
Y-287865D01*
Y-286865D01*
X320472D01*
X345161Y-292913D02*
Y-291581D01*
X345827Y-290914D01*
X346494Y-291581D01*
Y-292913D01*
Y-291914D01*
X345161D01*
X333465Y-292913D02*
Y-291581D01*
X334131Y-290914D01*
X334798Y-291581D01*
Y-292913D01*
Y-291914D01*
X333465D01*
X339370Y-286162D02*
Y-284829D01*
X340037Y-284162D01*
X340703Y-284829D01*
Y-286162D01*
Y-285162D01*
X339370D01*
Y-298819D02*
Y-297486D01*
X340037Y-296819D01*
X340703Y-297486D01*
Y-298819D01*
Y-297819D01*
X339370D01*
X329134Y-228740D02*
Y-227407D01*
X329800Y-226741D01*
X330467Y-227407D01*
Y-228740D01*
Y-227741D01*
X329134D01*
X341274Y-242913D02*
Y-241581D01*
X341941Y-240914D01*
X342607Y-241581D01*
Y-242913D01*
Y-241914D01*
X341274D01*
X340786Y-235827D02*
Y-234494D01*
X341452Y-233827D01*
X342118Y-234494D01*
Y-235827D01*
Y-234827D01*
X340786D01*
X312322Y-236221D02*
Y-234888D01*
X312989Y-234221D01*
X313655Y-234888D01*
Y-236221D01*
Y-235221D01*
X312322D01*
X309782Y-243307D02*
Y-241974D01*
X310449Y-241308D01*
X311115Y-241974D01*
Y-243307D01*
Y-242307D01*
X309782D01*
X334842Y-247244D02*
Y-245911D01*
X335509Y-245245D01*
X336175Y-245911D01*
Y-247244D01*
Y-246244D01*
X334842D01*
X319685Y-245276D02*
Y-243943D01*
X320352Y-243276D01*
X321018Y-243943D01*
Y-245276D01*
Y-244276D01*
X319685D01*
X333714Y-239764D02*
Y-238431D01*
X334380Y-237764D01*
X335047Y-238431D01*
Y-239764D01*
Y-238764D01*
X333714D01*
X325590Y-246324D02*
Y-244991D01*
X326257Y-244324D01*
X326923Y-244991D01*
Y-246324D01*
Y-245324D01*
X325590D01*
Y-232344D02*
Y-231011D01*
X326257Y-230345D01*
X326923Y-231011D01*
Y-232344D01*
Y-231344D01*
X325590D01*
X317009Y-239764D02*
Y-238431D01*
X317675Y-237764D01*
X318342Y-238431D01*
Y-239764D01*
Y-238764D01*
X317009D01*
X390896Y-249065D02*
Y-247732D01*
X391562Y-247066D01*
X392229Y-247732D01*
Y-249065D01*
Y-248065D01*
X390896D01*
X386615Y-249113D02*
Y-247780D01*
X387282Y-247114D01*
X387948Y-247780D01*
Y-249113D01*
Y-248113D01*
X386615D01*
X400000Y-219291D02*
Y-217958D01*
X400666Y-217292D01*
X401333Y-217958D01*
Y-219291D01*
Y-218292D01*
X400000D01*
X398472Y-235531D02*
Y-234199D01*
X399139Y-233532D01*
X399805Y-234199D01*
Y-235531D01*
Y-234532D01*
X398472D01*
X378937Y-249803D02*
Y-248470D01*
X379604Y-247804D01*
X380270Y-248470D01*
Y-249803D01*
Y-248803D01*
X378937D01*
X367654Y-236614D02*
Y-235281D01*
X368320Y-234615D01*
X368987Y-235281D01*
Y-236614D01*
Y-235614D01*
X367654D01*
X373093Y-232972D02*
Y-231640D01*
X373760Y-230973D01*
X374426Y-231640D01*
Y-232972D01*
Y-231973D01*
X373093D01*
X375197Y-221260D02*
Y-219927D01*
X375863Y-219261D01*
X376530Y-219927D01*
Y-221260D01*
Y-220260D01*
X375197D01*
X382776Y-221555D02*
Y-220222D01*
X383442Y-219556D01*
X384108Y-220222D01*
Y-221555D01*
Y-220555D01*
X382776D01*
X368232Y-217717D02*
Y-216384D01*
X368898Y-215717D01*
X369565Y-216384D01*
Y-217717D01*
Y-216717D01*
X368232D01*
X390158Y-217717D02*
Y-216384D01*
X390824Y-215717D01*
X391490Y-216384D01*
Y-217717D01*
Y-216717D01*
X390158D01*
X415623Y-358391D02*
Y-357059D01*
X416289Y-356392D01*
X416956Y-357059D01*
Y-358391D01*
Y-357392D01*
X415623D01*
X414772Y-353273D02*
Y-351940D01*
X415439Y-351274D01*
X416105Y-351940D01*
Y-353273D01*
Y-352274D01*
X414772D01*
X449150Y-355832D02*
Y-354500D01*
X449817Y-353833D01*
X450483Y-354500D01*
Y-355832D01*
Y-354833D01*
X449150D01*
X460678Y-359179D02*
Y-357846D01*
X461344Y-357179D01*
X462010Y-357846D01*
Y-359179D01*
Y-358179D01*
X460678D01*
X460900Y-354061D02*
Y-352728D01*
X461566Y-352061D01*
X462233Y-352728D01*
Y-354061D01*
Y-353061D01*
X460900D01*
X493234Y-356620D02*
Y-355287D01*
X493900Y-354620D01*
X494567Y-355287D01*
Y-356620D01*
Y-355620D01*
X493234D01*
X533931Y-356296D02*
Y-354963D01*
X534597Y-354297D01*
X535263Y-354963D01*
Y-356296D01*
Y-355297D01*
X533931D01*
X499525Y-358855D02*
Y-357522D01*
X500192Y-356856D01*
X500858Y-357522D01*
Y-358855D01*
Y-357856D01*
X499525D01*
X499302Y-353737D02*
Y-352404D01*
X499968Y-351738D01*
X500634Y-352404D01*
Y-353737D01*
Y-352738D01*
X499302D01*
X579072Y-356690D02*
Y-355357D01*
X579738Y-354691D01*
X580405Y-355357D01*
Y-356690D01*
Y-355690D01*
X579072D01*
X561330Y-356099D02*
Y-354767D01*
X561997Y-354100D01*
X562663Y-354767D01*
Y-356099D01*
Y-355100D01*
X561330D01*
X543698Y-358659D02*
Y-357326D01*
X544364Y-356659D01*
X545031Y-357326D01*
Y-358659D01*
Y-357659D01*
X543698D01*
X543718Y-353540D02*
Y-352207D01*
X544385Y-351541D01*
X545051Y-352207D01*
Y-353540D01*
Y-352541D01*
X543718D01*
X626987Y-228346D02*
Y-227014D01*
X627654Y-226347D01*
X628320Y-227014D01*
Y-228346D01*
Y-227347D01*
X626987D01*
X605512Y-261024D02*
Y-259691D01*
X606178Y-259024D01*
X606845Y-259691D01*
Y-261024D01*
Y-260024D01*
X605512D01*
Y-256693D02*
Y-255360D01*
X606178Y-254694D01*
X606845Y-255360D01*
Y-256693D01*
Y-255693D01*
X605512D01*
X622835Y-244094D02*
Y-242762D01*
X623501Y-242095D01*
X624168Y-242762D01*
Y-244094D01*
Y-243095D01*
X622835D01*
Y-235433D02*
Y-234100D01*
X623501Y-233434D01*
X624168Y-234100D01*
Y-235433D01*
Y-234433D01*
X622835D01*
X618504Y-252362D02*
Y-251029D01*
X619170Y-250363D01*
X619837Y-251029D01*
Y-252362D01*
Y-251362D01*
X618504D01*
X622101Y-250000D02*
Y-248667D01*
X622768Y-248001D01*
X623434Y-248667D01*
Y-250000D01*
Y-249000D01*
X622101D01*
X622803Y-241006D02*
Y-239673D01*
X623470Y-239007D01*
X624136Y-239673D01*
Y-241006D01*
Y-240006D01*
X622803D01*
X605317Y-252756D02*
Y-251423D01*
X605984Y-250757D01*
X606650Y-251423D01*
Y-252756D01*
Y-251756D01*
X605317D01*
X610236Y-300000D02*
Y-298667D01*
X610903Y-298001D01*
X611569Y-298667D01*
Y-300000D01*
Y-299000D01*
X610236D01*
X619148Y-302756D02*
Y-301423D01*
X619815Y-300757D01*
X620481Y-301423D01*
Y-302756D01*
Y-301756D01*
X619148D01*
X622221Y-313481D02*
Y-312148D01*
X622887Y-311481D01*
X623554Y-312148D01*
Y-313481D01*
Y-312481D01*
X622221D01*
X622753Y-353307D02*
Y-351974D01*
X623420Y-351308D01*
X624086Y-351974D01*
Y-353307D01*
Y-352307D01*
X622753D01*
X622677Y-333307D02*
Y-331974D01*
X623344Y-331308D01*
X624010Y-331974D01*
Y-333307D01*
Y-332307D01*
X622677D01*
X623228Y-343307D02*
Y-341974D01*
X623895Y-341308D01*
X624561Y-341974D01*
Y-343307D01*
Y-342307D01*
X623228D01*
X598583Y-353307D02*
Y-351974D01*
X599249Y-351308D01*
X599916Y-351974D01*
Y-353307D01*
Y-352307D01*
X598583D01*
X598819Y-343307D02*
Y-341974D01*
X599485Y-341308D01*
X600152Y-341974D01*
Y-343307D01*
Y-342307D01*
X598819D01*
X598959Y-333307D02*
Y-331974D01*
X599626Y-331308D01*
X600292Y-331974D01*
Y-333307D01*
Y-332307D01*
X598959D01*
X598898Y-313307D02*
Y-311974D01*
X599564Y-311308D01*
X600231Y-311974D01*
Y-313307D01*
Y-312307D01*
X598898D01*
X393701Y-168898D02*
Y-167565D01*
X394367Y-166898D01*
X395034Y-167565D01*
Y-168898D01*
Y-167898D01*
X393701D01*
X378594Y-166966D02*
Y-165633D01*
X379260Y-164967D01*
X379927Y-165633D01*
Y-166966D01*
Y-165967D01*
X378594D01*
X348031Y-165748D02*
Y-164415D01*
X348698Y-163749D01*
X349364Y-164415D01*
Y-165748D01*
Y-164748D01*
X348031D01*
X342808Y-166966D02*
Y-165633D01*
X343475Y-164967D01*
X344141Y-165633D01*
Y-166966D01*
Y-165967D01*
X342808D01*
X337795Y-181102D02*
Y-179770D01*
X338462Y-179103D01*
X339128Y-179770D01*
Y-181102D01*
Y-180103D01*
X337795D01*
X334252Y-180315D02*
Y-178982D01*
X334918Y-178316D01*
X335585Y-178982D01*
Y-180315D01*
Y-179315D01*
X334252D01*
X310236Y-165748D02*
Y-164415D01*
X310903Y-163749D01*
X311569Y-164415D01*
Y-165748D01*
Y-164748D01*
X310236D01*
X309055Y-195669D02*
Y-194336D01*
X309722Y-193670D01*
X310388Y-194336D01*
Y-195669D01*
Y-194670D01*
X309055D01*
X314675Y-198819D02*
Y-197486D01*
X315341Y-196820D01*
X316008Y-197486D01*
Y-198819D01*
Y-197819D01*
X314675D01*
X319291Y-196850D02*
Y-195518D01*
X319958Y-194851D01*
X320624Y-195518D01*
Y-196850D01*
Y-195851D01*
X319291D01*
X322835Y-196063D02*
Y-194730D01*
X323501Y-194064D01*
X324167Y-194730D01*
Y-196063D01*
Y-195063D01*
X322835D01*
X373730Y-202888D02*
Y-201555D01*
X374396Y-200889D01*
X375063Y-201555D01*
Y-202888D01*
Y-201889D01*
X373730D01*
X375698Y-197700D02*
Y-196367D01*
X376364Y-195701D01*
X377031Y-196367D01*
Y-197700D01*
Y-196700D01*
X375698D01*
X383572Y-206205D02*
Y-204872D01*
X384239Y-204205D01*
X384905Y-204872D01*
Y-206205D01*
Y-205205D01*
X383572D01*
X385541Y-202460D02*
Y-201127D01*
X386208Y-200461D01*
X386874Y-201127D01*
Y-202460D01*
Y-201461D01*
X385541D01*
X155427Y-33907D02*
Y-32574D01*
X156093Y-31908D01*
X156760Y-32574D01*
Y-33907D01*
Y-32907D01*
X155427D01*
X155328Y-26033D02*
Y-24700D01*
X155994Y-24034D01*
X156660Y-24700D01*
Y-26033D01*
Y-25033D01*
X155328D01*
X122539Y-26033D02*
Y-24700D01*
X123205Y-24034D01*
X123872Y-24700D01*
Y-26033D01*
Y-25033D01*
X122539D01*
X142126Y-348031D02*
Y-346699D01*
X142792Y-346032D01*
X143459Y-346699D01*
Y-348031D01*
Y-347032D01*
X142126D01*
X141587Y-352161D02*
Y-350829D01*
X142254Y-350162D01*
X142920Y-350829D01*
Y-352161D01*
Y-351162D01*
X141587D01*
X377658Y-346144D02*
Y-344812D01*
X378324Y-344145D01*
X378991Y-344812D01*
Y-346144D01*
Y-345145D01*
X377658D01*
X256890Y-374655D02*
Y-373322D01*
X257556Y-372656D01*
X258223Y-373322D01*
Y-374655D01*
Y-373655D01*
X256890D01*
X380807Y-346144D02*
Y-344812D01*
X381474Y-344145D01*
X382140Y-344812D01*
Y-346144D01*
Y-345145D01*
X380807D01*
X253655Y-374421D02*
Y-373088D01*
X254322Y-372422D01*
X254988Y-373088D01*
Y-374421D01*
Y-373421D01*
X253655D01*
X269502Y-374291D02*
Y-372958D01*
X270169Y-372292D01*
X270835Y-372958D01*
Y-374291D01*
Y-373291D01*
X269502D01*
X273425Y-374655D02*
Y-373322D01*
X274092Y-372656D01*
X274758Y-373322D01*
Y-374655D01*
Y-373655D01*
X273425D01*
X374114Y-328034D02*
Y-326701D01*
X374781Y-326035D01*
X375447Y-326701D01*
Y-328034D01*
Y-327034D01*
X374114D01*
X371359Y-328034D02*
Y-326701D01*
X372025Y-326035D01*
X372691Y-326701D01*
Y-328034D01*
Y-327034D01*
X371359D01*
X478895Y-331073D02*
X479695Y-330273D01*
X480495Y-331073D01*
X479695Y-331873D01*
X478895Y-331073D01*
X581257Y-92884D02*
X582058Y-92084D01*
X582858Y-92884D01*
X582058Y-93684D01*
X581257Y-92884D01*
X478895D02*
X479695Y-92084D01*
X480495Y-92884D01*
X479695Y-93684D01*
X478895Y-92884D01*
X581257Y-331073D02*
X582058Y-330273D01*
X582858Y-331073D01*
X582058Y-331873D01*
X581257Y-331073D01*
X22047Y-335433D02*
Y-334100D01*
X22714Y-333434D01*
X23380Y-334100D01*
Y-335433D01*
Y-334433D01*
X22047D01*
X2097Y-349213D02*
Y-347880D01*
X2764Y-347213D01*
X3430Y-347880D01*
Y-349213D01*
Y-348213D01*
X2097D01*
X27067Y-282677D02*
Y-281344D01*
X27733Y-280678D01*
X28400Y-281344D01*
Y-282677D01*
Y-281678D01*
X27067D01*
X5584Y-238905D02*
Y-237572D01*
X6250Y-236905D01*
X6916Y-237572D01*
Y-238905D01*
Y-237905D01*
X5584D01*
X35120Y-228937D02*
Y-227604D01*
X35787Y-226938D01*
X36453Y-227604D01*
Y-228937D01*
Y-227937D01*
X35120D01*
X10630Y-197638D02*
Y-196305D01*
X11296Y-195638D01*
X11963Y-196305D01*
Y-197638D01*
Y-196638D01*
X10630D01*
X19976Y-200787D02*
Y-199454D01*
X20643Y-198788D01*
X21309Y-199454D01*
Y-200787D01*
Y-199788D01*
X19976D01*
Y-220472D02*
Y-219140D01*
X20643Y-218473D01*
X21309Y-219140D01*
Y-220472D01*
Y-219473D01*
X19976D01*
X22441Y-168123D02*
X21641Y-166523D01*
X23241D01*
X22441Y-168123D01*
X19685D02*
X18885Y-166523D01*
X20485D01*
X19685Y-168123D01*
X16929D02*
X16129Y-166523D01*
X17729D01*
X16929Y-168123D01*
X23228Y-148044D02*
X22428Y-146444D01*
X24028D01*
X23228Y-148044D01*
X20079D02*
X19279Y-146444D01*
X20879D01*
X20079Y-148044D01*
X17323D02*
X16523Y-146444D01*
X18123D01*
X17323Y-148044D01*
X27165Y-179134D02*
Y-177801D01*
X27832Y-177135D01*
X28498Y-177801D01*
Y-179134D01*
Y-178134D01*
X27165D01*
X-7874Y-188976D02*
Y-187644D01*
X-7208Y-186977D01*
X-6541Y-187644D01*
Y-188976D01*
Y-187977D01*
X-7874D01*
X364173Y-332283D02*
Y-330951D01*
X364840Y-330284D01*
X365506Y-330951D01*
Y-332283D01*
Y-331284D01*
X364173D01*
X370079Y-332283D02*
Y-330951D01*
X370745Y-330284D01*
X371412Y-330951D01*
Y-332283D01*
Y-331284D01*
X370079D01*
X377658Y-327985D02*
Y-326652D01*
X378324Y-325986D01*
X378991Y-326652D01*
Y-327985D01*
Y-326986D01*
X377658D01*
X369703Y-326432D02*
Y-325099D01*
X370369Y-324432D01*
X371036Y-325099D01*
Y-326432D01*
Y-325432D01*
X369703D01*
X344882Y-328346D02*
Y-327014D01*
X345548Y-326347D01*
X346215Y-327014D01*
Y-328346D01*
Y-327347D01*
X344882D01*
X348425Y-328740D02*
Y-327407D01*
X349092Y-326741D01*
X349758Y-327407D01*
Y-328740D01*
Y-327741D01*
X348425D01*
X381989Y-348458D02*
Y-347125D01*
X382655Y-346458D01*
X383321Y-347125D01*
Y-348458D01*
Y-347458D01*
X381989D01*
X376870Y-348458D02*
Y-347125D01*
X377537Y-346458D01*
X378203Y-347125D01*
Y-348458D01*
Y-347458D01*
X376870D01*
X374902Y-348458D02*
Y-347125D01*
X375568Y-346458D01*
X376235Y-347125D01*
Y-348458D01*
Y-347458D01*
X374902D01*
X370472Y-348425D02*
Y-347092D01*
X371139Y-346426D01*
X371805Y-347092D01*
Y-348425D01*
Y-347426D01*
X370472D01*
X368294Y-348913D02*
Y-347580D01*
X368960Y-346914D01*
X369627Y-347580D01*
Y-348913D01*
Y-347913D01*
X368294D01*
X363878Y-348458D02*
Y-347125D01*
X364545Y-346458D01*
X365211Y-347125D01*
Y-348458D01*
Y-347458D01*
X363878D01*
X361910Y-348458D02*
Y-347125D01*
X362576Y-346458D01*
X363243Y-347125D01*
Y-348458D01*
Y-347458D01*
X361910D01*
X356792Y-348458D02*
Y-347125D01*
X357458Y-346458D01*
X358124Y-347125D01*
Y-348458D01*
Y-347458D01*
X356792D01*
X349705Y-348064D02*
Y-346731D01*
X350372Y-346065D01*
X351038Y-346731D01*
Y-348064D01*
Y-347064D01*
X349705D01*
X354823Y-348851D02*
Y-347519D01*
X355490Y-346852D01*
X356156Y-347519D01*
Y-348851D01*
Y-347852D01*
X354823D01*
X156693Y-18110D02*
Y-16777D01*
X157359Y-16111D01*
X158026Y-16777D01*
Y-18110D01*
Y-17111D01*
X156693D01*
X203689Y-248906D02*
Y-247573D01*
X204355Y-246906D01*
X205022Y-247573D01*
Y-248906D01*
Y-247906D01*
X203689D01*
X203937Y-242913D02*
Y-241581D01*
X204604Y-240914D01*
X205270Y-241581D01*
Y-242913D01*
Y-241914D01*
X203937D01*
X451674Y-283940D02*
Y-282607D01*
X452340Y-281940D01*
X453006Y-282607D01*
Y-283940D01*
Y-282940D01*
X451674D01*
X381989Y-331971D02*
Y-330638D01*
X382655Y-329972D01*
X383321Y-330638D01*
Y-331971D01*
Y-330972D01*
X381989D01*
X370178Y-315042D02*
Y-313709D01*
X370844Y-313043D01*
X371510Y-313709D01*
Y-315042D01*
Y-314042D01*
X370178D01*
X342618Y-315081D02*
Y-313748D01*
X343285Y-313082D01*
X343951Y-313748D01*
Y-315081D01*
Y-314082D01*
X342618D01*
X451674Y-234727D02*
Y-233394D01*
X452340Y-232728D01*
X453006Y-233394D01*
Y-234727D01*
Y-233727D01*
X451674D01*
X258702Y-264859D02*
Y-263526D01*
X259369Y-262860D01*
X260035Y-263526D01*
Y-264859D01*
Y-263859D01*
X258702D01*
X445768Y-254381D02*
Y-253048D01*
X446434Y-252381D01*
X447101Y-253048D01*
Y-254381D01*
Y-253381D01*
X445768D01*
X359874Y-183841D02*
Y-182508D01*
X360541Y-181842D01*
X361207Y-182508D01*
Y-183841D01*
Y-182842D01*
X359874D01*
X263322Y-246466D02*
Y-245133D01*
X263988Y-244466D01*
X264654Y-245133D01*
Y-246466D01*
Y-245466D01*
X263322D01*
X340847Y-179215D02*
Y-177882D01*
X341513Y-177216D01*
X342180Y-177882D01*
Y-179215D01*
Y-178216D01*
X340847D01*
X451674Y-244570D02*
Y-243237D01*
X452340Y-242570D01*
X453006Y-243237D01*
Y-244570D01*
Y-243570D01*
X451674D01*
X258760Y-256529D02*
Y-255196D01*
X259427Y-254529D01*
X260093Y-255196D01*
Y-256529D01*
Y-255529D01*
X258760D01*
X445768Y-264255D02*
Y-262922D01*
X446434Y-262255D01*
X447101Y-262922D01*
Y-264255D01*
Y-263255D01*
X445768D01*
X350327Y-183546D02*
Y-182213D01*
X350993Y-181547D01*
X351660Y-182213D01*
Y-183546D01*
Y-182546D01*
X350327D01*
X263622Y-236666D02*
Y-235333D01*
X264288Y-234666D01*
X264954Y-235333D01*
Y-236666D01*
Y-235666D01*
X263622D01*
X352461Y-315042D02*
Y-313709D01*
X353127Y-313043D01*
X353794Y-313709D01*
Y-315042D01*
Y-314042D01*
X352461D01*
X330705Y-179215D02*
Y-177882D01*
X331371Y-177216D01*
X332038Y-177882D01*
Y-179215D01*
Y-178216D01*
X330705D01*
X263122Y-285766D02*
Y-284433D01*
X263788Y-283766D01*
X264455Y-284433D01*
Y-285766D01*
Y-284766D01*
X263122D01*
X364272Y-315042D02*
Y-313709D01*
X364938Y-313043D01*
X365605Y-313709D01*
Y-315042D01*
Y-314042D01*
X364272D01*
X343012Y-332365D02*
Y-331032D01*
X343679Y-330365D01*
X344345Y-331032D01*
Y-332365D01*
Y-331365D01*
X343012D01*
X451674Y-254381D02*
Y-253048D01*
X452340Y-252381D01*
X453006Y-253048D01*
Y-254381D01*
Y-253381D01*
X451674D01*
X350327Y-179215D02*
Y-177882D01*
X350993Y-177216D01*
X351660Y-177882D01*
Y-179215D01*
Y-178216D01*
X350327D01*
X258622Y-246466D02*
Y-245133D01*
X259288Y-244466D01*
X259955Y-245133D01*
Y-246466D01*
Y-245466D01*
X258622D01*
X322933Y-332365D02*
Y-331032D01*
X323600Y-330365D01*
X324266Y-331032D01*
Y-332365D01*
Y-331365D01*
X322933D01*
X445768Y-275261D02*
Y-273928D01*
X446434Y-273262D01*
X447101Y-273928D01*
Y-275261D01*
Y-274261D01*
X445768D01*
X340256Y-183841D02*
Y-182508D01*
X340923Y-181842D01*
X341589Y-182508D01*
Y-183841D01*
Y-182842D01*
X340256D01*
X263580Y-226943D02*
Y-225610D01*
X264247Y-224944D01*
X264913Y-225610D01*
Y-226943D01*
Y-225944D01*
X263580D01*
X445768Y-224885D02*
Y-223552D01*
X446434Y-222885D01*
X447101Y-223552D01*
Y-224885D01*
Y-223885D01*
X445768D01*
X320473Y-179117D02*
Y-177784D01*
X321139Y-177118D01*
X321806Y-177784D01*
Y-179117D01*
Y-178117D01*
X320473D01*
X263322Y-276066D02*
Y-274733D01*
X263988Y-274066D01*
X264654Y-274733D01*
Y-276066D01*
Y-275066D01*
X263322D01*
X352106Y-332482D02*
Y-331149D01*
X352772Y-330482D01*
X353438Y-331149D01*
Y-332482D01*
Y-331482D01*
X352106D01*
X451674Y-264255D02*
Y-262922D01*
X452340Y-262255D01*
X453006Y-262922D01*
Y-264255D01*
Y-263255D01*
X451674D01*
X259022Y-236566D02*
Y-235233D01*
X259688Y-234566D01*
X260354Y-235233D01*
Y-236566D01*
Y-235566D01*
X259022D01*
X322540Y-315042D02*
Y-313709D01*
X323206Y-313043D01*
X323873Y-313709D01*
Y-315042D01*
Y-314042D01*
X322540D01*
X445768Y-283940D02*
Y-282607D01*
X446434Y-281940D01*
X447101Y-282607D01*
Y-283940D01*
Y-282940D01*
X445768D01*
X331091Y-184050D02*
Y-182717D01*
X331757Y-182051D01*
X332424Y-182717D01*
Y-184050D01*
Y-183050D01*
X331091D01*
X258622Y-285766D02*
Y-284433D01*
X259288Y-283766D01*
X259955Y-284433D01*
Y-285766D01*
Y-284766D01*
X258622D01*
X376477Y-315042D02*
Y-313709D01*
X377143Y-313043D01*
X377810Y-313709D01*
Y-315042D01*
Y-314042D01*
X376477D01*
X357973Y-315042D02*
Y-313709D01*
X358639Y-313043D01*
X359306Y-313709D01*
Y-315042D01*
Y-314042D01*
X357973D01*
X445768Y-234727D02*
Y-233394D01*
X446434Y-232728D01*
X447101Y-233394D01*
Y-234727D01*
Y-233727D01*
X445768D01*
X379496Y-183803D02*
Y-182470D01*
X380163Y-181804D01*
X380829Y-182470D01*
Y-183803D01*
Y-182803D01*
X379496D01*
Y-179215D02*
Y-177882D01*
X380163Y-177215D01*
X380829Y-177882D01*
Y-179215D01*
Y-178215D01*
X379496D01*
X262922Y-265040D02*
Y-263707D01*
X263588Y-263040D01*
X264254Y-263707D01*
Y-265040D01*
Y-264040D01*
X262922D01*
X332776Y-332365D02*
Y-331032D01*
X333442Y-330365D01*
X334109Y-331032D01*
Y-332365D01*
Y-331365D01*
X332776D01*
X451674Y-275261D02*
Y-273928D01*
X452340Y-273262D01*
X453006Y-273928D01*
Y-275261D01*
Y-274261D01*
X451674D01*
X369981Y-179215D02*
Y-177882D01*
X370647Y-177216D01*
X371314Y-177882D01*
Y-179215D01*
Y-178216D01*
X369981D01*
X258922Y-226766D02*
Y-225433D01*
X259588Y-224766D01*
X260255Y-225433D01*
Y-226766D01*
Y-225766D01*
X258922D01*
X451674Y-224885D02*
Y-223552D01*
X452340Y-222885D01*
X453006Y-223552D01*
Y-224885D01*
Y-223885D01*
X451674D01*
X360138Y-179215D02*
Y-177882D01*
X360805Y-177216D01*
X361471Y-177882D01*
Y-179215D01*
Y-178216D01*
X360138D01*
X258622Y-276066D02*
Y-274733D01*
X259288Y-274066D01*
X259955Y-274733D01*
Y-276066D01*
Y-275066D01*
X258622D01*
X381595Y-315042D02*
Y-313709D01*
X382261Y-313043D01*
X382928Y-313709D01*
Y-315042D01*
Y-314042D01*
X381595D01*
X445768Y-244570D02*
Y-243237D01*
X446434Y-242570D01*
X447101Y-243237D01*
Y-244570D01*
Y-243570D01*
X445768D01*
X369685Y-183841D02*
Y-182508D01*
X370352Y-181842D01*
X371018Y-182508D01*
Y-183841D01*
Y-182842D01*
X369685D01*
X263681Y-256529D02*
Y-255196D01*
X264348Y-254529D01*
X265014Y-255196D01*
Y-256529D01*
Y-255529D01*
X263681D01*
X332382Y-315042D02*
Y-313709D01*
X333049Y-313043D01*
X333715Y-313709D01*
Y-315042D01*
Y-314042D01*
X332382D01*
X19976Y-252953D02*
Y-251620D01*
X20643Y-250953D01*
X21309Y-251620D01*
Y-252953D01*
Y-251953D01*
X19976D01*
Y-272638D02*
Y-271305D01*
X20643Y-270638D01*
X21309Y-271305D01*
Y-272638D01*
Y-271638D01*
X19976D01*
Y-326772D02*
Y-325439D01*
X20643Y-324772D01*
X21309Y-325439D01*
Y-326772D01*
Y-325772D01*
X19976D01*
Y-307087D02*
Y-305754D01*
X20643Y-305087D01*
X21309Y-305754D01*
Y-307087D01*
Y-306087D01*
X19976D01*
X100729Y-123872D02*
Y-122539D01*
X101396Y-121872D01*
X102062Y-122539D01*
Y-123872D01*
Y-122872D01*
X100729D01*
X163071Y-390730D02*
Y-389397D01*
X163737Y-388731D01*
X164404Y-389397D01*
Y-390730D01*
Y-389730D01*
X163071D01*
X259285Y-390247D02*
Y-388914D01*
X259952Y-388247D01*
X260618Y-388914D01*
Y-390247D01*
Y-389247D01*
X259285D01*
X267204Y-390009D02*
Y-388677D01*
X267871Y-388010D01*
X268537Y-388677D01*
Y-390009D01*
Y-389010D01*
X267204D01*
X216162Y-390947D02*
Y-389614D01*
X216829Y-388948D01*
X217495Y-389614D01*
Y-390947D01*
Y-389948D01*
X216162D01*
X235144Y-390416D02*
Y-389083D01*
X235811Y-388416D01*
X236477Y-389083D01*
Y-390416D01*
Y-389416D01*
X235144D01*
X251456Y-390009D02*
Y-388677D01*
X252123Y-388010D01*
X252789Y-388677D01*
Y-390009D01*
Y-389010D01*
X251456D01*
X226063Y-390722D02*
Y-389389D01*
X226729Y-388723D01*
X227396Y-389389D01*
Y-390722D01*
Y-389722D01*
X226063D01*
X281201Y-390009D02*
Y-388677D01*
X281867Y-388010D01*
X282534Y-388677D01*
Y-390009D01*
Y-389010D01*
X281201D01*
X174941Y-390600D02*
Y-389267D01*
X175607Y-388601D01*
X176274Y-389267D01*
Y-390600D01*
Y-389600D01*
X174941D01*
X202441Y-390600D02*
Y-389267D01*
X203107Y-388601D01*
X203774Y-389267D01*
Y-390600D01*
Y-389600D01*
X202441D01*
X-23622Y-187992D02*
Y-186659D01*
X-22956Y-185993D01*
X-22289Y-186659D01*
Y-187992D01*
Y-186993D01*
X-23622D01*
X26772Y-348819D02*
Y-347486D01*
X27438Y-346819D01*
X28105Y-347486D01*
Y-348819D01*
Y-347819D01*
X26772D01*
X-1181Y-352831D02*
Y-351498D01*
X-515Y-350831D01*
X152Y-351498D01*
Y-352831D01*
Y-351831D01*
X-1181D01*
X4331Y-344488D02*
Y-343155D01*
X4997Y-342489D01*
X5664Y-343155D01*
Y-344488D01*
Y-343489D01*
X4331D01*
X12598Y-349213D02*
Y-347880D01*
X13265Y-347213D01*
X13931Y-347880D01*
Y-349213D01*
Y-348213D01*
X12598D01*
X35039Y-289961D02*
Y-288628D01*
X35706Y-287961D01*
X36372Y-288628D01*
Y-289961D01*
Y-288961D01*
X35039D01*
Y-285827D02*
Y-284494D01*
X35706Y-283827D01*
X36372Y-284494D01*
Y-285827D01*
Y-284827D01*
X35039D01*
X27067Y-298727D02*
Y-297394D01*
X27733Y-296727D01*
X28400Y-297394D01*
Y-298727D01*
Y-297727D01*
X27067D01*
X10630Y-292126D02*
Y-290793D01*
X11296Y-290127D01*
X11963Y-290793D01*
Y-292126D01*
Y-291126D01*
X10630D01*
X14173Y-294320D02*
Y-292987D01*
X14840Y-292320D01*
X15506Y-292987D01*
Y-294320D01*
Y-293320D01*
X14173D01*
X288Y-234968D02*
Y-233635D01*
X955Y-232968D01*
X1621Y-233635D01*
Y-234968D01*
Y-233968D01*
X288D01*
X10007Y-234968D02*
Y-233635D01*
X10674Y-232968D01*
X11340Y-233635D01*
Y-234968D01*
Y-233968D01*
X10007D01*
X19685Y-239370D02*
Y-238037D01*
X20351Y-237371D01*
X21018Y-238037D01*
Y-239370D01*
Y-238370D01*
X19685D01*
X14665Y-237402D02*
Y-236069D01*
X15332Y-235402D01*
X15998Y-236069D01*
Y-237402D01*
Y-236402D01*
X14665D01*
X36220Y-235039D02*
Y-233706D01*
X36887Y-233040D01*
X37553Y-233706D01*
Y-235039D01*
Y-234040D01*
X36220D01*
X36614Y-232677D02*
Y-231344D01*
X37281Y-230678D01*
X37947Y-231344D01*
Y-232677D01*
Y-231678D01*
X36614D01*
X35039Y-237402D02*
Y-236069D01*
X35706Y-235402D01*
X36372Y-236069D01*
Y-237402D01*
Y-236402D01*
X35039D01*
X30709Y-190411D02*
Y-189078D01*
X31375Y-188412D01*
X32042Y-189078D01*
Y-190411D01*
Y-189411D01*
X30709D01*
X33071Y-185755D02*
Y-184422D01*
X33737Y-183756D01*
X34404Y-184422D01*
Y-185755D01*
Y-184755D01*
X33071D01*
X35827Y-185755D02*
Y-184422D01*
X36493Y-183756D01*
X37160Y-184422D01*
Y-185755D01*
Y-184755D01*
X35827D01*
X13780Y-190551D02*
Y-189218D01*
X14446Y-188552D01*
X15112Y-189218D01*
Y-190551D01*
Y-189551D01*
X13780D01*
X9843Y-185755D02*
Y-184422D01*
X10509Y-183756D01*
X11175Y-184422D01*
Y-185755D01*
Y-184755D01*
X9843D01*
X19682Y-192520D02*
Y-191187D01*
X20348Y-190520D01*
X21015Y-191187D01*
Y-192520D01*
Y-191520D01*
X19682D01*
X-10630Y-178347D02*
Y-177014D01*
X-9963Y-176347D01*
X-9297Y-177014D01*
Y-178347D01*
Y-177347D01*
X-10630D01*
X198392Y-366842D02*
Y-365509D01*
X199059Y-364843D01*
X199725Y-365509D01*
Y-366842D01*
Y-365842D01*
X198392D01*
X196701Y-370523D02*
Y-369190D01*
X197367Y-368524D01*
X198034Y-369190D01*
Y-370523D01*
Y-369523D01*
X196701D01*
X394193Y-197670D02*
Y-196337D01*
X394860Y-195671D01*
X395526Y-196337D01*
Y-197670D01*
Y-196671D01*
X394193D01*
X380363Y-196740D02*
Y-195407D01*
X381030Y-194741D01*
X381696Y-195407D01*
Y-196740D01*
Y-195740D01*
X380363D01*
X157480Y-361811D02*
Y-360478D01*
X158147Y-359812D01*
X158813Y-360478D01*
Y-361811D01*
Y-360811D01*
X157480D01*
X153543Y-358661D02*
Y-357329D01*
X154210Y-356662D01*
X154876Y-357329D01*
Y-358661D01*
Y-357662D01*
X153543D01*
Y-361811D02*
Y-360478D01*
X154210Y-359812D01*
X154876Y-360478D01*
Y-361811D01*
Y-360811D01*
X153543D01*
X155512Y-361811D02*
Y-360478D01*
X156178Y-359812D01*
X156845Y-360478D01*
Y-361811D01*
Y-360811D01*
X155512D01*
Y-358661D02*
Y-357329D01*
X156178Y-356662D01*
X156845Y-357329D01*
Y-358661D01*
Y-357662D01*
X155512D01*
X157480Y-358661D02*
Y-357329D01*
X158147Y-356662D01*
X158813Y-357329D01*
Y-358661D01*
Y-357662D01*
X157480D01*
X157087Y-41732D02*
Y-40399D01*
X157753Y-39733D01*
X158420Y-40399D01*
Y-41732D01*
Y-40733D01*
X157087D01*
X230165Y-235119D02*
Y-233786D01*
X230831Y-233120D01*
X231498Y-233786D01*
Y-235119D01*
Y-234120D01*
X230165D01*
X246162Y-293733D02*
Y-292401D01*
X246828Y-291734D01*
X247495Y-292401D01*
Y-293733D01*
Y-292734D01*
X246162D01*
X230406Y-251861D02*
Y-250529D01*
X231072Y-249862D01*
X231739Y-250529D01*
Y-251861D01*
Y-250862D01*
X230406D01*
X230251Y-232266D02*
Y-230933D01*
X230917Y-230267D01*
X231583Y-230933D01*
Y-232266D01*
Y-231267D01*
X230251D01*
X204331Y-232677D02*
Y-231344D01*
X204997Y-230678D01*
X205664Y-231344D01*
Y-232677D01*
Y-231678D01*
X204331D01*
X203937Y-235827D02*
Y-234494D01*
X204604Y-233827D01*
X205270Y-234494D01*
Y-235827D01*
Y-234827D01*
X203937D01*
Y-238189D02*
Y-236856D01*
X204604Y-236190D01*
X205270Y-236856D01*
Y-238189D01*
Y-237189D01*
X203937D01*
X203805Y-240564D02*
Y-239232D01*
X204472Y-238565D01*
X205138Y-239232D01*
Y-240564D01*
Y-239565D01*
X203805D01*
X203805Y-252182D02*
Y-250849D01*
X204472Y-250182D01*
X205138Y-250849D01*
Y-252182D01*
Y-251182D01*
X203805D01*
X203937Y-254724D02*
Y-253392D01*
X204604Y-252725D01*
X205270Y-253392D01*
Y-254724D01*
Y-253725D01*
X203937D01*
X154724Y-389616D02*
Y-388283D01*
X155391Y-387616D01*
X156057Y-388283D01*
Y-389616D01*
Y-388616D01*
X154724D01*
X156693Y-389616D02*
Y-388283D01*
X157359Y-387616D01*
X158026Y-388283D01*
Y-389616D01*
Y-388616D01*
X156693D01*
X158661Y-389616D02*
Y-388283D01*
X159328Y-387616D01*
X159994Y-388283D01*
Y-389616D01*
Y-388616D01*
X158661D01*
X154724Y-386466D02*
Y-385133D01*
X155391Y-384467D01*
X156057Y-385133D01*
Y-386466D01*
Y-385467D01*
X154724D01*
X156693Y-386466D02*
Y-385133D01*
X157359Y-384467D01*
X158026Y-385133D01*
Y-386466D01*
Y-385467D01*
X156693D01*
X158661Y-386466D02*
Y-385133D01*
X159328Y-384467D01*
X159994Y-385133D01*
Y-386466D01*
Y-385467D01*
X158661D01*
X280414Y-293782D02*
Y-292449D01*
X281080Y-291783D01*
X281747Y-292449D01*
Y-293782D01*
Y-292782D01*
X280414D01*
X245965Y-264497D02*
Y-263164D01*
X246631Y-262498D01*
X247298Y-263164D01*
Y-264497D01*
Y-263497D01*
X245965D01*
Y-254655D02*
Y-253322D01*
X246631Y-252655D01*
X247298Y-253322D01*
Y-254655D01*
Y-253655D01*
X245965D01*
X432835Y-291755D02*
Y-290422D01*
X433501Y-289756D01*
X434168Y-290422D01*
Y-291755D01*
Y-290755D01*
X432835D01*
X472047Y-221260D02*
Y-219927D01*
X472714Y-219261D01*
X473380Y-219927D01*
Y-221260D01*
Y-220260D01*
X472047D01*
X430020Y-218979D02*
Y-217646D01*
X430686Y-216980D01*
X431353Y-217646D01*
Y-218979D01*
Y-217979D01*
X430020D01*
X472047Y-223228D02*
Y-221895D01*
X472714Y-221229D01*
X473380Y-221895D01*
Y-223228D01*
Y-222229D01*
X472047D01*
X430020Y-220948D02*
Y-219615D01*
X430686Y-218948D01*
X431353Y-219615D01*
Y-220948D01*
Y-219948D01*
X430020D01*
Y-222916D02*
Y-221583D01*
X430686Y-220917D01*
X431353Y-221583D01*
Y-222916D01*
Y-221916D01*
X430020D01*
X472047Y-219291D02*
Y-217958D01*
X472714Y-217292D01*
X473380Y-217958D01*
Y-219291D01*
Y-218292D01*
X472047D01*
X430020Y-217010D02*
Y-215678D01*
X430686Y-215011D01*
X431353Y-215678D01*
Y-217010D01*
Y-216011D01*
X430020D01*
X121457Y-57529D02*
Y-56196D01*
X122123Y-55530D01*
X122790Y-56196D01*
Y-57529D01*
Y-56529D01*
X121457D01*
X280382Y-274277D02*
Y-272944D01*
X281048Y-272277D01*
X281715Y-272944D01*
Y-274277D01*
Y-273277D01*
X280382D01*
X337774Y-196489D02*
Y-195156D01*
X338440Y-194490D01*
X339107Y-195156D01*
Y-196489D01*
Y-195490D01*
X337774D01*
X274719Y-244928D02*
Y-243595D01*
X275385Y-242929D01*
X276052Y-243595D01*
Y-244928D01*
Y-243929D01*
X274719D01*
X276755Y-246539D02*
Y-245206D01*
X277421Y-244540D01*
X278088Y-245206D01*
Y-246539D01*
Y-245540D01*
X276755D01*
X280414Y-283478D02*
Y-282145D01*
X281080Y-281479D01*
X281747Y-282145D01*
Y-283478D01*
Y-282478D01*
X280414D01*
Y-287478D02*
Y-286145D01*
X281080Y-285479D01*
X281747Y-286145D01*
Y-287478D01*
Y-286478D01*
X280414D01*
X331220Y-196266D02*
Y-194934D01*
X331887Y-194267D01*
X332553Y-194934D01*
Y-196266D01*
Y-195267D01*
X331220D01*
X341774Y-196326D02*
Y-194993D01*
X342440Y-194327D01*
X343107Y-194993D01*
Y-196326D01*
Y-195326D01*
X341774D01*
X326705Y-179059D02*
Y-177726D01*
X327372Y-177060D01*
X328038Y-177726D01*
Y-179059D01*
Y-178059D01*
X326705D01*
X324705Y-184678D02*
Y-183345D01*
X325372Y-182679D01*
X326038Y-183345D01*
Y-184678D01*
Y-183679D01*
X324705D01*
X463453Y-247883D02*
Y-246550D01*
X464119Y-245884D01*
X464786Y-246550D01*
Y-247883D01*
Y-246884D01*
X463453D01*
X464472Y-245540D02*
Y-244207D01*
X465138Y-243541D01*
X465805Y-244207D01*
Y-245540D01*
Y-244540D01*
X464472D01*
X327658Y-184678D02*
Y-183345D01*
X328324Y-182679D01*
X328991Y-183345D01*
Y-184678D01*
Y-183679D01*
X327658D01*
X36614Y18701D02*
Y20034D01*
X37281Y20700D01*
X37947Y20034D01*
Y18701D01*
Y19701D01*
X36614D01*
X244028Y-262466D02*
Y-261133D01*
X244694Y-260466D01*
X245361Y-261133D01*
Y-262466D01*
Y-261466D01*
X244028D01*
Y-258497D02*
Y-257164D01*
X244694Y-256498D01*
X245361Y-257164D01*
Y-258497D01*
Y-257498D01*
X244028D01*
X243996Y-252592D02*
Y-251259D01*
X244663Y-250592D01*
X245329Y-251259D01*
Y-252592D01*
Y-251592D01*
X243996D01*
X245965Y-250655D02*
Y-249322D01*
X246631Y-248655D01*
X247298Y-249322D01*
Y-250655D01*
Y-249655D01*
X245965D01*
X243996Y-248655D02*
Y-247322D01*
X244663Y-246655D01*
X245329Y-247322D01*
Y-248655D01*
Y-247655D01*
X243996D01*
X245965Y-260497D02*
Y-259164D01*
X246631Y-258498D01*
X247298Y-259164D01*
Y-260497D01*
Y-259497D01*
X245965D01*
X-23622Y-342520D02*
Y-341187D01*
X-22956Y-340520D01*
X-22289Y-341187D01*
Y-342520D01*
Y-341520D01*
X-23622D01*
X100729Y-119871D02*
Y-118539D01*
X101396Y-117872D01*
X102062Y-118539D01*
Y-119871D01*
Y-118872D01*
X100729D01*
X-23622Y-229331D02*
Y-227998D01*
X-22956Y-227331D01*
X-22289Y-227998D01*
Y-229331D01*
Y-228331D01*
X-23622D01*
Y-233268D02*
Y-231935D01*
X-22956Y-231268D01*
X-22289Y-231935D01*
Y-233268D01*
Y-232268D01*
X-23622D01*
Y-237205D02*
Y-235872D01*
X-22956Y-235205D01*
X-22289Y-235872D01*
Y-237205D01*
Y-236205D01*
X-23622D01*
Y-241142D02*
Y-239809D01*
X-22956Y-239142D01*
X-22289Y-239809D01*
Y-241142D01*
Y-240142D01*
X-23622D01*
Y-282480D02*
Y-281147D01*
X-22956Y-280481D01*
X-22289Y-281147D01*
Y-282480D01*
Y-281481D01*
X-23622D01*
Y-286417D02*
Y-285084D01*
X-22956Y-284418D01*
X-22289Y-285084D01*
Y-286417D01*
Y-285418D01*
X-23622D01*
Y-290354D02*
Y-289021D01*
X-22956Y-288355D01*
X-22289Y-289021D01*
Y-290354D01*
Y-289355D01*
X-23622D01*
Y-294291D02*
Y-292958D01*
X-22956Y-292292D01*
X-22289Y-292958D01*
Y-294291D01*
Y-293292D01*
X-23622D01*
Y-335630D02*
Y-334297D01*
X-22956Y-333631D01*
X-22289Y-334297D01*
Y-335630D01*
Y-334630D01*
X-23622D01*
Y-339567D02*
Y-338234D01*
X-22956Y-337568D01*
X-22289Y-338234D01*
Y-339567D01*
Y-338567D01*
X-23622D01*
Y-66929D02*
Y-65596D01*
X-22956Y-64930D01*
X-22289Y-65596D01*
Y-66929D01*
Y-65929D01*
X-23622D01*
Y-62992D02*
Y-61659D01*
X-22956Y-60993D01*
X-22289Y-61659D01*
Y-62992D01*
Y-61992D01*
X-23622D01*
Y-60039D02*
Y-58706D01*
X-22956Y-58040D01*
X-22289Y-58706D01*
Y-60039D01*
Y-59040D01*
X-23622D01*
Y-102362D02*
Y-101029D01*
X-22956Y-100363D01*
X-22289Y-101029D01*
Y-102362D01*
Y-101363D01*
X-23622D01*
Y-106299D02*
Y-104966D01*
X-22956Y-104300D01*
X-22289Y-104966D01*
Y-106299D01*
Y-105299D01*
X-23622D01*
Y-110236D02*
Y-108903D01*
X-22956Y-108237D01*
X-22289Y-108903D01*
Y-110236D01*
Y-109237D01*
X-23622D01*
Y-184055D02*
Y-182722D01*
X-22956Y-182056D01*
X-22289Y-182722D01*
Y-184055D01*
Y-183055D01*
X-23622D01*
Y-177165D02*
Y-175832D01*
X-22956Y-175166D01*
X-22289Y-175832D01*
Y-177165D01*
Y-176166D01*
X-23622D01*
X472047Y-217323D02*
Y-215990D01*
X472714Y-215323D01*
X473380Y-215990D01*
Y-217323D01*
Y-216323D01*
X472047D01*
X190354Y-377411D02*
Y-376078D01*
X191021Y-375412D01*
X191687Y-376078D01*
Y-377411D01*
Y-376411D01*
X190354D01*
X178543Y-377411D02*
Y-376078D01*
X179210Y-375412D01*
X179876Y-376078D01*
Y-377411D01*
Y-376411D01*
X178543D01*
X362598Y-197244D02*
Y-195911D01*
X363265Y-195245D01*
X363931Y-195911D01*
Y-197244D01*
Y-196244D01*
X362598D01*
X36762Y11811D02*
Y13144D01*
X37429Y13810D01*
X38095Y13144D01*
Y11811D01*
Y12811D01*
X36762D01*
X36614Y4921D02*
Y6254D01*
X37281Y6921D01*
X37947Y6254D01*
Y4921D01*
Y5921D01*
X36614D01*
Y-1969D02*
Y-636D01*
X37281Y31D01*
X37947Y-636D01*
Y-1969D01*
Y-969D01*
X36614D01*
X389567Y-196440D02*
Y-195107D01*
X390234Y-194440D01*
X390900Y-195107D01*
Y-196440D01*
Y-195440D01*
X389567D01*
X432579Y-283251D02*
Y-281918D01*
X433246Y-281251D01*
X433912Y-281918D01*
Y-283251D01*
Y-282251D01*
X432579D01*
Y-286400D02*
Y-285067D01*
X433246Y-284401D01*
X433912Y-285067D01*
Y-286400D01*
Y-285401D01*
X432579D01*
X432720Y-289358D02*
Y-288025D01*
X433387Y-287358D01*
X434053Y-288025D01*
Y-289358D01*
Y-288358D01*
X432720D01*
D294*
X603909Y-805D02*
G03*
X603909Y-805I-800J0D01*
G01*
X195682Y394D02*
G03*
X195682Y394I-800J0D01*
G01*
X497257Y-271358D02*
G03*
X497257Y-271358I-800J0D01*
G01*
D295*
X195282Y394D02*
G03*
X195282Y394I-400J0D01*
G01*
X496857Y-271358D02*
G03*
X496857Y-271358I-400J0D01*
G01*
M02*
